G04 ================== begin FILE IDENTIFICATION RECORD ==================*
G04 Layout Name:  D:/<user>/Wistron_project/16316-1/gbr-0621/16316-1.brd*
G04 Film Name:    TSMD*
G04 File Format:  Gerber RS274X*
G04 File Origin:  Cadence Allegro 16.5-S056*
G04 Origin Date:  Wed Jun 21 09:31:51 2017*
G04 *
G04 Layer:  VIA CLASS/PASTEMASK_TOP*
G04 Layer:  PIN/PASTEMASK_TOP*
G04 Layer:  PACKAGE GEOMETRY/PASTEMASK_TOP*
G04 Layer:  DRAWING FORMAT/LAYER_PCB_STORY*
G04 Layer:  DRAWING FORMAT/LAYER_PAST_T*
G04 Layer:  BOARD GEOMETRY/PANEL_OUTLINE*
G04 *
G04 Offset:    (0.00 0.00)*
G04 Mirror:    No*
G04 Mode:      Positive*
G04 Rotation:  0*
G04 FullContactRelief:  No*
G04 UndefLineWidth:     6.00*
G04 ================== end FILE IDENTIFICATION RECORD ====================*
%FSLAX35Y35*MOIN*%
%IR0*IPPOS*OFA0.00000B0.00000*MIA0B0*SFA1.00000B1.00000*%
%AMMACRO66*
4,1,40,.013,.017,
-.013,.017,
-.013695,.016939,
-.014368,.016759,
-.015,.016464,
-.015571,.016064,
-.016064,.015571,
-.016464,.015,
-.016759,.014368,
-.016939,.013695,
-.017,.013,
-.017,-.013,
-.016939,-.013695,
-.016759,-.014368,
-.016464,-.015,
-.016064,-.015571,
-.015571,-.016064,
-.015,-.016464,
-.014368,-.016759,
-.013695,-.016939,
-.013,-.017,
.013,-.017,
.013695,-.016939,
.014368,-.016759,
.015,-.016464,
.015571,-.016064,
.016064,-.015571,
.016464,-.015,
.016759,-.014368,
.016939,-.013695,
.017,-.013,
.017,.013,
.016939,.013695,
.016759,.014368,
.016464,.015,
.016064,.015571,
.015571,.016064,
.015,.016464,
.014368,.016759,
.013695,.016939,
.013,.017,
0.0*
%
%ADD66MACRO66*%
%AMMACRO34*
4,1,40,.017,-.013,
.017,.013,
.016939,.013695,
.016759,.014368,
.016464,.015,
.016064,.015571,
.015571,.016064,
.015,.016464,
.014368,.016759,
.013695,.016939,
.013,.017,
-.013,.017,
-.013695,.016939,
-.014368,.016759,
-.015,.016464,
-.015571,.016064,
-.016064,.015571,
-.016464,.015,
-.016759,.014368,
-.016939,.013695,
-.017,.013,
-.017,-.013,
-.016939,-.013695,
-.016759,-.014368,
-.016464,-.015,
-.016064,-.015571,
-.015571,-.016064,
-.015,-.016464,
-.014368,-.016759,
-.013695,-.016939,
-.013,-.017,
.013,-.017,
.013695,-.016939,
.014368,-.016759,
.015,-.016464,
.015571,-.016064,
.016064,-.015571,
.016464,-.015,
.016759,-.014368,
.016939,-.013695,
.017,-.013,
0.0*
%
%ADD34MACRO34*%
%AMMACRO72*
4,1,3,-.0125,.025,
.0125,0.0,
-.0125,-.025,
-.0125,.025,
0.0*
%
%ADD72MACRO72*%
%ADD97R,.143X.011*%
%AMMACRO55*
4,1,3,0.0,-.0125,
-.025,.0125,
.025,.0125,
0.0,-.0125,
0.0*
%
%ADD55MACRO55*%
%ADD77C,.02*%
%ADD64R,.122X.093*%
%ADD10C,.04*%
%ADD91C,.014*%
%AMMACRO81*
4,1,40,-.007,.004,
-.007,-.004,
-.00697,-.004347,
-.006879,-.004684,
-.006732,-.005,
-.006532,-.005286,
-.006286,-.005532,
-.006,-.005732,
-.005684,-.005879,
-.005347,-.00597,
-.005,-.006,
.005,-.006,
.005347,-.00597,
.005684,-.005879,
.006,-.005732,
.006286,-.005532,
.006532,-.005286,
.006732,-.005,
.006879,-.004684,
.00697,-.004347,
.007,-.004,
.007,.004,
.00697,.004347,
.006879,.004684,
.006732,.005,
.006532,.005286,
.006286,.005532,
.006,.005732,
.005684,.005879,
.005347,.00597,
.005,.006,
-.005,.006,
-.005347,.00597,
-.005684,.005879,
-.006,.005732,
-.006286,.005532,
-.006532,.005286,
-.006732,.005,
-.006879,.004684,
-.00697,.004347,
-.007,.004,
0.0*
%
%ADD81MACRO81*%
%ADD62R,.06X.008*%
%ADD84R,.008X.06*%
%ADD92C,.016*%
%ADD51R,.039X.108*%
%ADD28C,.026*%
%ADD88R,.039X.118*%
%ADD76C,.018*%
%ADD75C,.028*%
%ADD94R,.098X.128*%
%AMMACRO87*
4,1,40,.008,-.014,
-.008,-.014,
-.008695,-.013939,
-.009368,-.013759,
-.01,-.013464,
-.010571,-.013064,
-.011064,-.012571,
-.011464,-.012,
-.011759,-.011368,
-.011939,-.010695,
-.012,-.01,
-.012,.01,
-.011939,.010695,
-.011759,.011368,
-.011464,.012,
-.011064,.012571,
-.010571,.013064,
-.01,.013464,
-.009368,.013759,
-.008695,.013939,
-.008,.014,
.008,.014,
.008695,.013939,
.009368,.013759,
.01,.013464,
.010571,.013064,
.011064,.012571,
.011464,.012,
.011759,.011368,
.011939,.010695,
.012,.01,
.012,-.01,
.011939,-.010695,
.011759,-.011368,
.011464,-.012,
.011064,-.012571,
.010571,-.013064,
.01,-.013464,
.009368,-.013759,
.008695,-.013939,
.008,-.014,
0.0*
%
%ADD87MACRO87*%
%AMMACRO41*
4,1,40,.0225,-.007,
.022378,-.008389,
.022018,-.009736,
.021428,-.011,
.020628,-.012142,
.019642,-.013128,
.0185,-.013928,
.017236,-.014518,
.015889,-.014878,
.0145,-.015,
-.0145,-.015,
-.015889,-.014878,
-.017236,-.014518,
-.0185,-.013928,
-.019642,-.013128,
-.020628,-.012142,
-.021428,-.011,
-.022018,-.009736,
-.022378,-.008389,
-.0225,-.007,
-.0225,.007,
-.022378,.008389,
-.022018,.009736,
-.021428,.011,
-.020628,.012142,
-.019642,.013128,
-.0185,.013928,
-.017236,.014518,
-.015889,.014878,
-.0145,.015,
.0145,.015,
.015889,.014878,
.017236,.014518,
.0185,.013928,
.019642,.013128,
.020628,.012142,
.021428,.011,
.022018,.009736,
.022378,.008389,
.0225,.007,
.0225,-.007,
0.0*
%
%ADD41MACRO41*%
%AMMACRO95*
4,1,40,-.007,-.0225,
-.008389,-.022378,
-.009736,-.022018,
-.011,-.021428,
-.012142,-.020628,
-.013128,-.019642,
-.013928,-.0185,
-.014518,-.017236,
-.014878,-.015889,
-.015,-.0145,
-.015,.0145,
-.014878,.015889,
-.014518,.017236,
-.013928,.0185,
-.013128,.019642,
-.012142,.020628,
-.011,.021428,
-.009736,.022018,
-.008389,.022378,
-.007,.0225,
.007,.0225,
.008389,.022378,
.009736,.022018,
.011,.021428,
.012142,.020628,
.013128,.019642,
.013928,.0185,
.014518,.017236,
.014878,.015889,
.015,.0145,
.015,-.0145,
.014878,-.015889,
.014518,-.017236,
.013928,-.0185,
.013128,-.019642,
.012142,-.020628,
.011,-.021428,
.009736,-.022018,
.008389,-.022378,
.007,-.0225,
-.007,-.0225,
0.0*
%
%ADD95MACRO95*%
%ADD59R,.065X.065*%
%AMMACRO19*
4,1,40,.011,-.007,
.011,.007,
.010939,.007695,
.010759,.008368,
.010464,.009,
.010064,.009571,
.009571,.010064,
.009,.010464,
.008368,.010759,
.007695,.010939,
.007,.011,
-.007,.011,
-.007695,.010939,
-.008368,.010759,
-.009,.010464,
-.009571,.010064,
-.010064,.009571,
-.010464,.009,
-.010759,.008368,
-.010939,.007695,
-.011,.007,
-.011,-.007,
-.010939,-.007695,
-.010759,-.008368,
-.010464,-.009,
-.010064,-.009571,
-.009571,-.010064,
-.009,-.010464,
-.008368,-.010759,
-.007695,-.010939,
-.007,-.011,
.007,-.011,
.007695,-.010939,
.008368,-.010759,
.009,-.010464,
.009571,-.010064,
.010064,-.009571,
.010464,-.009,
.010759,-.008368,
.010939,-.007695,
.011,-.007,
0.0*
%
%ADD19MACRO19*%
%AMMACRO11*
4,1,40,.007,.011,
-.007,.011,
-.007695,.010939,
-.008368,.010759,
-.009,.010464,
-.009571,.010064,
-.010064,.009571,
-.010464,.009,
-.010759,.008368,
-.010939,.007695,
-.011,.007,
-.011,-.007,
-.010939,-.007695,
-.010759,-.008368,
-.010464,-.009,
-.010064,-.009571,
-.009571,-.010064,
-.009,-.010464,
-.008368,-.010759,
-.007695,-.010939,
-.007,-.011,
.007,-.011,
.007695,-.010939,
.008368,-.010759,
.009,-.010464,
.009571,-.010064,
.010064,-.009571,
.010464,-.009,
.010759,-.008368,
.010939,-.007695,
.011,-.007,
.011,.007,
.010939,.007695,
.010759,.008368,
.010464,.009,
.010064,.009571,
.009571,.010064,
.009,.010464,
.008368,.010759,
.007695,.010939,
.007,.011,
0.0*
%
%ADD11MACRO11*%
%AMMACRO43*
4,1,40,-.012,.008,
-.012,-.008,
-.011939,-.008695,
-.011759,-.009368,
-.011464,-.01,
-.011064,-.010571,
-.010571,-.011064,
-.01,-.011464,
-.009368,-.011759,
-.008695,-.011939,
-.008,-.012,
.008,-.012,
.008695,-.011939,
.009368,-.011759,
.01,-.011464,
.010571,-.011064,
.011064,-.010571,
.011464,-.01,
.011759,-.009368,
.011939,-.008695,
.012,-.008,
.012,.008,
.011939,.008695,
.011759,.009368,
.011464,.01,
.011064,.010571,
.010571,.011064,
.01,.011464,
.009368,.011759,
.008695,.011939,
.008,.012,
-.008,.012,
-.008695,.011939,
-.009368,.011759,
-.01,.011464,
-.010571,.011064,
-.011064,.010571,
-.011464,.01,
-.011759,.009368,
-.011939,.008695,
-.012,.008,
0.0*
%
%ADD43MACRO43*%
%AMMACRO18*
4,1,40,.008,.012,
-.008,.012,
-.008695,.011939,
-.009368,.011759,
-.01,.011464,
-.010571,.011064,
-.011064,.010571,
-.011464,.01,
-.011759,.009368,
-.011939,.008695,
-.012,.008,
-.012,-.008,
-.011939,-.008695,
-.011759,-.009368,
-.011464,-.01,
-.011064,-.010571,
-.010571,-.011064,
-.01,-.011464,
-.009368,-.011759,
-.008695,-.011939,
-.008,-.012,
.008,-.012,
.008695,-.011939,
.009368,-.011759,
.01,-.011464,
.010571,-.011064,
.011064,-.010571,
.011464,-.01,
.011759,-.009368,
.011939,-.008695,
.012,-.008,
.012,.008,
.011939,.008695,
.011759,.009368,
.011464,.01,
.011064,.010571,
.010571,.011064,
.01,.011464,
.009368,.011759,
.008695,.011939,
.008,.012,
0.0*
%
%ADD18MACRO18*%
%AMMACRO48*
4,1,40,-.013,-.017,
.013,-.017,
.013695,-.016939,
.014368,-.016759,
.015,-.016464,
.015571,-.016064,
.016064,-.015571,
.016464,-.015,
.016759,-.014368,
.016939,-.013695,
.017,-.013,
.017,.013,
.016939,.013695,
.016759,.014368,
.016464,.015,
.016064,.015571,
.015571,.016064,
.015,.016464,
.014368,.016759,
.013695,.016939,
.013,.017,
-.013,.017,
-.013695,.016939,
-.014368,.016759,
-.015,.016464,
-.015571,.016064,
-.016064,.015571,
-.016464,.015,
-.016759,.014368,
-.016939,.013695,
-.017,.013,
-.017,-.013,
-.016939,-.013695,
-.016759,-.014368,
-.016464,-.015,
-.016064,-.015571,
-.015571,-.016064,
-.015,-.016464,
-.014368,-.016759,
-.013695,-.016939,
-.013,-.017,
0.0*
%
%ADD48MACRO48*%
%AMMACRO31*
4,1,40,-.017,.013,
-.017,-.013,
-.016939,-.013695,
-.016759,-.014368,
-.016464,-.015,
-.016064,-.015571,
-.015571,-.016064,
-.015,-.016464,
-.014368,-.016759,
-.013695,-.016939,
-.013,-.017,
.013,-.017,
.013695,-.016939,
.014368,-.016759,
.015,-.016464,
.015571,-.016064,
.016064,-.015571,
.016464,-.015,
.016759,-.014368,
.016939,-.013695,
.017,-.013,
.017,.013,
.016939,.013695,
.016759,.014368,
.016464,.015,
.016064,.015571,
.015571,.016064,
.015,.016464,
.014368,.016759,
.013695,.016939,
.013,.017,
-.013,.017,
-.013695,.016939,
-.014368,.016759,
-.015,.016464,
-.015571,.016064,
-.016064,.015571,
-.016464,.015,
-.016759,.014368,
-.016939,.013695,
-.017,.013,
0.0*
%
%ADD31MACRO31*%
%AMMACRO20*
4,1,40,.011,-.007,
.011,.007,
.010939,.007695,
.010759,.008368,
.010464,.009,
.010064,.009571,
.009571,.010064,
.009,.010464,
.008368,.010759,
.007695,.010939,
.007,.011,
-.007,.011,
-.007695,.010939,
-.008368,.010759,
-.009,.010464,
-.009571,.010064,
-.010064,.009571,
-.010464,.009,
-.010759,.008368,
-.010939,.007695,
-.011,.007,
-.011,-.007,
-.010939,-.007695,
-.010759,-.008368,
-.010464,-.009,
-.010064,-.009571,
-.009571,-.010064,
-.009,-.010464,
-.008368,-.010759,
-.007695,-.010939,
-.007,-.011,
.007,-.011,
.007695,-.010939,
.008368,-.010759,
.009,-.010464,
.009571,-.010064,
.010064,-.009571,
.010464,-.009,
.010759,-.008368,
.010939,-.007695,
.011,-.007,
0.0*
%
%ADD20MACRO20*%
%AMMACRO12*
4,1,40,.007,.011,
-.007,.011,
-.007695,.010939,
-.008368,.010759,
-.009,.010464,
-.009571,.010064,
-.010064,.009571,
-.010464,.009,
-.010759,.008368,
-.010939,.007695,
-.011,.007,
-.011,-.007,
-.010939,-.007695,
-.010759,-.008368,
-.010464,-.009,
-.010064,-.009571,
-.009571,-.010064,
-.009,-.010464,
-.008368,-.010759,
-.007695,-.010939,
-.007,-.011,
.007,-.011,
.007695,-.010939,
.008368,-.010759,
.009,-.010464,
.009571,-.010064,
.010064,-.009571,
.010464,-.009,
.010759,-.008368,
.010939,-.007695,
.011,-.007,
.011,.007,
.010939,.007695,
.010759,.008368,
.010464,.009,
.010064,.009571,
.009571,.010064,
.009,.010464,
.008368,.010759,
.007695,.010939,
.007,.011,
0.0*
%
%ADD12MACRO12*%
%AMMACRO89*
4,1,20,.0635,-.1075,
.049,-.1075,
.049,-.118,
.0395,-.118,
.0395,-.1075,
-.0395,-.1075,
-.0395,-.118,
-.049,-.118,
-.049,-.1075,
-.0635,-.1075,
-.0635,.1075,
-.049,.1075,
-.049,.118,
-.0395,.118,
-.0395,.1075,
.0395,.1075,
.0395,.118,
.049,.118,
.049,.1075,
.0635,.1075,
.0635,-.1075,
0.0*
%
%ADD89MACRO89*%
%AMMACRO67*
4,1,20,-.1075,-.0635,
-.1075,-.049,
-.118,-.049,
-.118,-.0395,
-.1075,-.0395,
-.1075,.0395,
-.118,.0395,
-.118,.049,
-.1075,.049,
-.1075,.0635,
.1075,.0635,
.1075,.049,
.118,.049,
.118,.0395,
.1075,.0395,
.1075,-.0395,
.118,-.0395,
.118,-.049,
.1075,-.049,
.1075,-.0635,
-.1075,-.0635,
0.0*
%
%ADD67MACRO67*%
%AMMACRO40*
4,1,40,-.012,.008,
-.012,-.008,
-.011939,-.008695,
-.011759,-.009368,
-.011464,-.01,
-.011064,-.010571,
-.010571,-.011064,
-.01,-.011464,
-.009368,-.011759,
-.008695,-.011939,
-.008,-.012,
.008,-.012,
.008695,-.011939,
.009368,-.011759,
.01,-.011464,
.010571,-.011064,
.011064,-.010571,
.011464,-.01,
.011759,-.009368,
.011939,-.008695,
.012,-.008,
.012,.008,
.011939,.008695,
.011759,.009368,
.011464,.01,
.011064,.010571,
.010571,.011064,
.01,.011464,
.009368,.011759,
.008695,.011939,
.008,.012,
-.008,.012,
-.008695,.011939,
-.009368,.011759,
-.01,.011464,
-.010571,.011064,
-.011064,.010571,
-.011464,.01,
-.011759,.009368,
-.011939,.008695,
-.012,.008,
0.0*
%
%ADD40MACRO40*%
%AMMACRO17*
4,1,40,.008,.012,
-.008,.012,
-.008695,.011939,
-.009368,.011759,
-.01,.011464,
-.010571,.011064,
-.011064,.010571,
-.011464,.01,
-.011759,.009368,
-.011939,.008695,
-.012,.008,
-.012,-.008,
-.011939,-.008695,
-.011759,-.009368,
-.011464,-.01,
-.011064,-.010571,
-.010571,-.011064,
-.01,-.011464,
-.009368,-.011759,
-.008695,-.011939,
-.008,-.012,
.008,-.012,
.008695,-.011939,
.009368,-.011759,
.01,-.011464,
.010571,-.011064,
.011064,-.010571,
.011464,-.01,
.011759,-.009368,
.011939,-.008695,
.012,-.008,
.012,.008,
.011939,.008695,
.011759,.009368,
.011464,.01,
.011064,.010571,
.010571,.011064,
.01,.011464,
.009368,.011759,
.008695,.011939,
.008,.012,
0.0*
%
%ADD17MACRO17*%
%AMMACRO49*
4,1,40,-.013,-.017,
.013,-.017,
.013695,-.016939,
.014368,-.016759,
.015,-.016464,
.015571,-.016064,
.016064,-.015571,
.016464,-.015,
.016759,-.014368,
.016939,-.013695,
.017,-.013,
.017,.013,
.016939,.013695,
.016759,.014368,
.016464,.015,
.016064,.015571,
.015571,.016064,
.015,.016464,
.014368,.016759,
.013695,.016939,
.013,.017,
-.013,.017,
-.013695,.016939,
-.014368,.016759,
-.015,.016464,
-.015571,.016064,
-.016064,.015571,
-.016464,.015,
-.016759,.014368,
-.016939,.013695,
-.017,.013,
-.017,-.013,
-.016939,-.013695,
-.016759,-.014368,
-.016464,-.015,
-.016064,-.015571,
-.015571,-.016064,
-.015,-.016464,
-.014368,-.016759,
-.013695,-.016939,
-.013,-.017,
0.0*
%
%ADD49MACRO49*%
%AMMACRO32*
4,1,40,-.017,.013,
-.017,-.013,
-.016939,-.013695,
-.016759,-.014368,
-.016464,-.015,
-.016064,-.015571,
-.015571,-.016064,
-.015,-.016464,
-.014368,-.016759,
-.013695,-.016939,
-.013,-.017,
.013,-.017,
.013695,-.016939,
.014368,-.016759,
.015,-.016464,
.015571,-.016064,
.016064,-.015571,
.016464,-.015,
.016759,-.014368,
.016939,-.013695,
.017,-.013,
.017,.013,
.016939,.013695,
.016759,.014368,
.016464,.015,
.016064,.015571,
.015571,.016064,
.015,.016464,
.014368,.016759,
.013695,.016939,
.013,.017,
-.013,.017,
-.013695,.016939,
-.014368,.016759,
-.015,.016464,
-.015571,.016064,
-.016064,.015571,
-.016464,.015,
-.016759,.014368,
-.016939,.013695,
-.017,.013,
0.0*
%
%ADD32MACRO32*%
%ADD99R,.011X.03*%
%ADD98R,.03X.011*%
%ADD54R,.126X.201*%
%AMMACRO79*
4,1,42,-.00768,.00246,
-.00602,-.00537,
-.005913,-.005702,
-.005755,-.006013,
-.005545,-.006291,
-.00529,-.006529,
-.004997,-.006719,
-.004676,-.006855,
-.004336,-.006933,
-.003988,-.006951,
-.003642,-.006908,
-.00364,-.00691,
.00614,-.00483,
.006473,-.004727,
.006784,-.004568,
.007062,-.004358,
.007299,-.004103,
.007489,-.003811,
.007625,-.00349,
.007703,-.00315,
.007721,-.002802,
.00768,-.00246,
.00602,.00537,
.005913,.005702,
.005755,.006013,
.005545,.006291,
.00529,.006529,
.004997,.006719,
.004676,.006855,
.004336,.006933,
.003988,.006951,
.003642,.006908,
.00364,.00691,
-.00614,.00483,
-.006473,.004727,
-.006784,.004568,
-.007062,.004358,
-.007299,.004103,
-.007489,.003811,
-.007625,.00349,
-.007703,.00315,
-.007721,.002802,
-.00768,.00246,
0.0*
%
%ADD79MACRO79*%
%AMMACRO56*
4,1,3,-.025,-.0125,
0.0,.0125,
.025,-.0125,
-.025,-.0125,
0.0*
%
%ADD56MACRO56*%
%ADD86R,.06X.012*%
%ADD83R,.022X.04*%
%AMMACRO71*
4,1,3,-.0125,0.0,
.0125,.025,
.0125,-.025,
-.0125,0.0,
0.0*
%
%ADD71MACRO71*%
%ADD38R,.042X.012*%
%ADD36R,.012X.042*%
%ADD104R,.06X.014*%
%ADD90R,.044X.012*%
%ADD102R,.014X.042*%
%ADD101R,.042X.014*%
%ADD82R,.105X.128*%
%ADD68R,.012X.044*%
%ADD44R,.014X.06*%
%ADD37R,.036X.012*%
%ADD35R,.012X.036*%
%ADD26R,.045X.03*%
%ADD69R,.128X.105*%
%ADD58R,.012X.036*%
%ADD57R,.036X.012*%
%ADD96R,.093X.011*%
%AMMACRO80*
4,1,40,.007,-.004,
.007,.004,
.00697,.004347,
.006879,.004684,
.006732,.005,
.006532,.005286,
.006286,.005532,
.006,.005732,
.005684,.005879,
.005347,.00597,
.005,.006,
-.005,.006,
-.005347,.00597,
-.005684,.005879,
-.006,.005732,
-.006286,.005532,
-.006532,.005286,
-.006732,.005,
-.006879,.004684,
-.00697,.004347,
-.007,.004,
-.007,-.004,
-.00697,-.004347,
-.006879,-.004684,
-.006732,-.005,
-.006532,-.005286,
-.006286,-.005532,
-.006,-.005732,
-.005684,-.005879,
-.005347,-.00597,
-.005,-.006,
.005,-.006,
.005347,-.00597,
.005684,-.005879,
.006,-.005732,
.006286,-.005532,
.006532,-.005286,
.006732,-.005,
.006879,-.004684,
.00697,-.004347,
.007,-.004,
0.0*
%
%ADD80MACRO80*%
%AMMACRO78*
4,1,40,-.004,-.007,
.004,-.007,
.004347,-.00697,
.004684,-.006879,
.005,-.006732,
.005286,-.006532,
.005532,-.006286,
.005732,-.006,
.005879,-.005684,
.00597,-.005347,
.006,-.005,
.006,.005,
.00597,.005347,
.005879,.005684,
.005732,.006,
.005532,.006286,
.005286,.006532,
.005,.006732,
.004684,.006879,
.004347,.00697,
.004,.007,
-.004,.007,
-.004347,.00697,
-.004684,.006879,
-.005,.006732,
-.005286,.006532,
-.005532,.006286,
-.005732,.006,
-.005879,.005684,
-.00597,.005347,
-.006,.005,
-.006,-.005,
-.00597,-.005347,
-.005879,-.005684,
-.005732,-.006,
-.005532,-.006286,
-.005286,-.006532,
-.005,-.006732,
-.004684,-.006879,
-.004347,-.00697,
-.004,-.007,
0.0*
%
%ADD78MACRO78*%
%ADD21R,.03X.064*%
%ADD93R,.05X.065*%
%ADD53R,.054X.025*%
%ADD70R,.065X.05*%
%ADD85R,.029X.043*%
%ADD42R,.065X.025*%
%ADD27R,.045X.09*%
%ADD73R,.043X.029*%
%ADD45R,.048X.016*%
%ADD24R,.045X.055*%
%ADD61R,.016X.048*%
%ADD39R,.13X.13*%
%ADD23R,.055X.045*%
%ADD103R,.06X.095*%
%ADD60R,.054X.075*%
%ADD50R,.054X.074*%
%ADD63R,.09X.095*%
%AMMACRO74*
4,1,40,-.0225,.007,
-.022378,.008389,
-.022018,.009736,
-.021428,.011,
-.020628,.012142,
-.019642,.013128,
-.0185,.013928,
-.017236,.014518,
-.015889,.014878,
-.0145,.015,
.0145,.015,
.015889,.014878,
.017236,.014518,
.0185,.013928,
.019642,.013128,
.020628,.012142,
.021428,.011,
.022018,.009736,
.022378,.008389,
.0225,.007,
.0225,-.007,
.022378,-.008389,
.022018,-.009736,
.021428,-.011,
.020628,-.012142,
.019642,-.013128,
.0185,-.013928,
.017236,-.014518,
.015889,-.014878,
.0145,-.015,
-.0145,-.015,
-.015889,-.014878,
-.017236,-.014518,
-.0185,-.013928,
-.019642,-.013128,
-.020628,-.012142,
-.021428,-.011,
-.022018,-.009736,
-.022378,-.008389,
-.0225,-.007,
-.0225,.007,
0.0*
%
%ADD74MACRO74*%
%AMMACRO52*
4,1,40,-.008,.014,
.008,.014,
.008695,.013939,
.009368,.013759,
.01,.013464,
.010571,.013064,
.011064,.012571,
.011464,.012,
.011759,.011368,
.011939,.010695,
.012,.01,
.012,-.01,
.011939,-.010695,
.011759,-.011368,
.011464,-.012,
.011064,-.012571,
.010571,-.013064,
.01,-.013464,
.009368,-.013759,
.008695,-.013939,
.008,-.014,
-.008,-.014,
-.008695,-.013939,
-.009368,-.013759,
-.01,-.013464,
-.010571,-.013064,
-.011064,-.012571,
-.011464,-.012,
-.011759,-.011368,
-.011939,-.010695,
-.012,-.01,
-.012,.01,
-.011939,.010695,
-.011759,.011368,
-.011464,.012,
-.011064,.012571,
-.010571,.013064,
-.01,.013464,
-.009368,.013759,
-.008695,.013939,
-.008,.014,
0.0*
%
%ADD52MACRO52*%
%AMMACRO25*
4,1,40,.007,.0225,
.008389,.022378,
.009736,.022018,
.011,.021428,
.012142,.020628,
.013128,.019642,
.013928,.0185,
.014518,.017236,
.014878,.015889,
.015,.0145,
.015,-.0145,
.014878,-.015889,
.014518,-.017236,
.013928,-.0185,
.013128,-.019642,
.012142,-.020628,
.011,-.021428,
.009736,-.022018,
.008389,-.022378,
.007,-.0225,
-.007,-.0225,
-.008389,-.022378,
-.009736,-.022018,
-.011,-.021428,
-.012142,-.020628,
-.013128,-.019642,
-.013928,-.0185,
-.014518,-.017236,
-.014878,-.015889,
-.015,-.0145,
-.015,.0145,
-.014878,.015889,
-.014518,.017236,
-.013928,.0185,
-.013128,.019642,
-.012142,.020628,
-.011,.021428,
-.009736,.022018,
-.008389,.022378,
-.007,.0225,
.007,.0225,
0.0*
%
%ADD25MACRO25*%
%ADD22R,.045X.059*%
%ADD100R,.128X.128*%
%AMMACRO47*
4,1,40,-.008,-.012,
.008,-.012,
.008695,-.011939,
.009368,-.011759,
.01,-.011464,
.010571,-.011064,
.011064,-.010571,
.011464,-.01,
.011759,-.009368,
.011939,-.008695,
.012,-.008,
.012,.008,
.011939,.008695,
.011759,.009368,
.011464,.01,
.011064,.010571,
.010571,.011064,
.01,.011464,
.009368,.011759,
.008695,.011939,
.008,.012,
-.008,.012,
-.008695,.011939,
-.009368,.011759,
-.01,.011464,
-.010571,.011064,
-.011064,.010571,
-.011464,.01,
-.011759,.009368,
-.011939,.008695,
-.012,.008,
-.012,-.008,
-.011939,-.008695,
-.011759,-.009368,
-.011464,-.01,
-.011064,-.010571,
-.010571,-.011064,
-.01,-.011464,
-.009368,-.011759,
-.008695,-.011939,
-.008,-.012,
0.0*
%
%ADD47MACRO47*%
%AMMACRO16*
4,1,40,.012,-.008,
.012,.008,
.011939,.008695,
.011759,.009368,
.011464,.01,
.011064,.010571,
.010571,.011064,
.01,.011464,
.009368,.011759,
.008695,.011939,
.008,.012,
-.008,.012,
-.008695,.011939,
-.009368,.011759,
-.01,.011464,
-.010571,.011064,
-.011064,.010571,
-.011464,.01,
-.011759,.009368,
-.011939,.008695,
-.012,.008,
-.012,-.008,
-.011939,-.008695,
-.011759,-.009368,
-.011464,-.01,
-.011064,-.010571,
-.010571,-.011064,
-.01,-.011464,
-.009368,-.011759,
-.008695,-.011939,
-.008,-.012,
.008,-.012,
.008695,-.011939,
.009368,-.011759,
.01,-.011464,
.010571,-.011064,
.011064,-.010571,
.011464,-.01,
.011759,-.009368,
.011939,-.008695,
.012,-.008,
0.0*
%
%ADD16MACRO16*%
%AMMACRO13*
4,1,40,-.007,-.011,
.007,-.011,
.007695,-.010939,
.008368,-.010759,
.009,-.010464,
.009571,-.010064,
.010064,-.009571,
.010464,-.009,
.010759,-.008368,
.010939,-.007695,
.011,-.007,
.011,.007,
.010939,.007695,
.010759,.008368,
.010464,.009,
.010064,.009571,
.009571,.010064,
.009,.010464,
.008368,.010759,
.007695,.010939,
.007,.011,
-.007,.011,
-.007695,.010939,
-.008368,.010759,
-.009,.010464,
-.009571,.010064,
-.010064,.009571,
-.010464,.009,
-.010759,.008368,
-.010939,.007695,
-.011,.007,
-.011,-.007,
-.010939,-.007695,
-.010759,-.008368,
-.010464,-.009,
-.010064,-.009571,
-.009571,-.010064,
-.009,-.010464,
-.008368,-.010759,
-.007695,-.010939,
-.007,-.011,
0.0*
%
%ADD13MACRO13*%
%AMMACRO29*
4,1,40,-.011,.007,
-.011,-.007,
-.010939,-.007695,
-.010759,-.008368,
-.010464,-.009,
-.010064,-.009571,
-.009571,-.010064,
-.009,-.010464,
-.008368,-.010759,
-.007695,-.010939,
-.007,-.011,
.007,-.011,
.007695,-.010939,
.008368,-.010759,
.009,-.010464,
.009571,-.010064,
.010064,-.009571,
.010464,-.009,
.010759,-.008368,
.010939,-.007695,
.011,-.007,
.011,.007,
.010939,.007695,
.010759,.008368,
.010464,.009,
.010064,.009571,
.009571,.010064,
.009,.010464,
.008368,.010759,
.007695,.010939,
.007,.011,
-.007,.011,
-.007695,.010939,
-.008368,.010759,
-.009,.010464,
-.009571,.010064,
-.010064,.009571,
-.010464,.009,
-.010759,.008368,
-.010939,.007695,
-.011,.007,
0.0*
%
%ADD29MACRO29*%
%AMMACRO65*
4,1,40,.013,.017,
-.013,.017,
-.013695,.016939,
-.014368,.016759,
-.015,.016464,
-.015571,.016064,
-.016064,.015571,
-.016464,.015,
-.016759,.014368,
-.016939,.013695,
-.017,.013,
-.017,-.013,
-.016939,-.013695,
-.016759,-.014368,
-.016464,-.015,
-.016064,-.015571,
-.015571,-.016064,
-.015,-.016464,
-.014368,-.016759,
-.013695,-.016939,
-.013,-.017,
.013,-.017,
.013695,-.016939,
.014368,-.016759,
.015,-.016464,
.015571,-.016064,
.016064,-.015571,
.016464,-.015,
.016759,-.014368,
.016939,-.013695,
.017,-.013,
.017,.013,
.016939,.013695,
.016759,.014368,
.016464,.015,
.016064,.015571,
.015571,.016064,
.015,.016464,
.014368,.016759,
.013695,.016939,
.013,.017,
0.0*
%
%ADD65MACRO65*%
%AMMACRO33*
4,1,40,.017,-.013,
.017,.013,
.016939,.013695,
.016759,.014368,
.016464,.015,
.016064,.015571,
.015571,.016064,
.015,.016464,
.014368,.016759,
.013695,.016939,
.013,.017,
-.013,.017,
-.013695,.016939,
-.014368,.016759,
-.015,.016464,
-.015571,.016064,
-.016064,.015571,
-.016464,.015,
-.016759,.014368,
-.016939,.013695,
-.017,.013,
-.017,-.013,
-.016939,-.013695,
-.016759,-.014368,
-.016464,-.015,
-.016064,-.015571,
-.015571,-.016064,
-.015,-.016464,
-.014368,-.016759,
-.013695,-.016939,
-.013,-.017,
.013,-.017,
.013695,-.016939,
.014368,-.016759,
.015,-.016464,
.015571,-.016064,
.016064,-.015571,
.016464,-.015,
.016759,-.014368,
.016939,-.013695,
.017,-.013,
0.0*
%
%ADD33MACRO33*%
%AMMACRO46*
4,1,40,-.008,-.012,
.008,-.012,
.008695,-.011939,
.009368,-.011759,
.01,-.011464,
.010571,-.011064,
.011064,-.010571,
.011464,-.01,
.011759,-.009368,
.011939,-.008695,
.012,-.008,
.012,.008,
.011939,.008695,
.011759,.009368,
.011464,.01,
.011064,.010571,
.010571,.011064,
.01,.011464,
.009368,.011759,
.008695,.011939,
.008,.012,
-.008,.012,
-.008695,.011939,
-.009368,.011759,
-.01,.011464,
-.010571,.011064,
-.011064,.010571,
-.011464,.01,
-.011759,.009368,
-.011939,.008695,
-.012,.008,
-.012,-.008,
-.011939,-.008695,
-.011759,-.009368,
-.011464,-.01,
-.011064,-.010571,
-.010571,-.011064,
-.01,-.011464,
-.009368,-.011759,
-.008695,-.011939,
-.008,-.012,
0.0*
%
%ADD46MACRO46*%
%AMMACRO15*
4,1,40,.012,-.008,
.012,.008,
.011939,.008695,
.011759,.009368,
.011464,.01,
.011064,.010571,
.010571,.011064,
.01,.011464,
.009368,.011759,
.008695,.011939,
.008,.012,
-.008,.012,
-.008695,.011939,
-.009368,.011759,
-.01,.011464,
-.010571,.011064,
-.011064,.010571,
-.011464,.01,
-.011759,.009368,
-.011939,.008695,
-.012,.008,
-.012,-.008,
-.011939,-.008695,
-.011759,-.009368,
-.011464,-.01,
-.011064,-.010571,
-.010571,-.011064,
-.01,-.011464,
-.009368,-.011759,
-.008695,-.011939,
-.008,-.012,
.008,-.012,
.008695,-.011939,
.009368,-.011759,
.01,-.011464,
.010571,-.011064,
.011064,-.010571,
.011464,-.01,
.011759,-.009368,
.011939,-.008695,
.012,-.008,
0.0*
%
%ADD15MACRO15*%
%AMMACRO14*
4,1,40,-.007,-.011,
.007,-.011,
.007695,-.010939,
.008368,-.010759,
.009,-.010464,
.009571,-.010064,
.010064,-.009571,
.010464,-.009,
.010759,-.008368,
.010939,-.007695,
.011,-.007,
.011,.007,
.010939,.007695,
.010759,.008368,
.010464,.009,
.010064,.009571,
.009571,.010064,
.009,.010464,
.008368,.010759,
.007695,.010939,
.007,.011,
-.007,.011,
-.007695,.010939,
-.008368,.010759,
-.009,.010464,
-.009571,.010064,
-.010064,.009571,
-.010464,.009,
-.010759,.008368,
-.010939,.007695,
-.011,.007,
-.011,-.007,
-.010939,-.007695,
-.010759,-.008368,
-.010464,-.009,
-.010064,-.009571,
-.009571,-.010064,
-.009,-.010464,
-.008368,-.010759,
-.007695,-.010939,
-.007,-.011,
0.0*
%
%ADD14MACRO14*%
%AMMACRO30*
4,1,40,-.011,.007,
-.011,-.007,
-.010939,-.007695,
-.010759,-.008368,
-.010464,-.009,
-.010064,-.009571,
-.009571,-.010064,
-.009,-.010464,
-.008368,-.010759,
-.007695,-.010939,
-.007,-.011,
.007,-.011,
.007695,-.010939,
.008368,-.010759,
.009,-.010464,
.009571,-.010064,
.010064,-.009571,
.010464,-.009,
.010759,-.008368,
.010939,-.007695,
.011,-.007,
.011,.007,
.010939,.007695,
.010759,.008368,
.010464,.009,
.010064,.009571,
.009571,.010064,
.009,.010464,
.008368,.010759,
.007695,.010939,
.007,.011,
-.007,.011,
-.007695,.010939,
-.008368,.010759,
-.009,.010464,
-.009571,.010064,
-.010064,.009571,
-.010464,.009,
-.010759,.008368,
-.010939,.007695,
-.011,.007,
0.0*
%
%ADD30MACRO30*%
%ADD105C,.006*%
G75*
%LPD*%
G75*
G36*
G01X40400Y138185D02*
X31850D01*
Y129235D01*
X40400D01*
Y138185D01*
G37*
G36*
G01X51550D02*
X43000D01*
Y129235D01*
X51550D01*
Y138185D01*
G37*
G36*
G01X40400Y126635D02*
X31850D01*
Y117685D01*
X40400D01*
Y126635D01*
G37*
G36*
G01X51550D02*
X43000D01*
Y117685D01*
X51550D01*
Y126635D01*
G37*
G54D100*
X694512Y457271D03*
G54D101*
X684769Y452153D03*
Y454712D03*
Y457271D03*
Y459830D03*
Y462389D03*
X704255D03*
Y459830D03*
Y457271D03*
Y454712D03*
Y452153D03*
G54D102*
X697071Y447528D03*
X694512D03*
X691953D03*
X689394D03*
Y467014D03*
X691953D03*
X694512D03*
X697071D03*
X699630Y447528D03*
Y467014D03*
G54D103*
X735512Y410241D03*
Y377189D03*
G54D10*
X37700Y64400D03*
X86150Y441700D03*
X365450Y179154D03*
X552000Y368500D03*
X630600Y221100D03*
X762300Y106300D03*
X737400Y485700D03*
G54D104*
X765018Y301111D03*
Y303671D03*
Y306231D03*
Y308791D03*
X781198D03*
Y306231D03*
Y303671D03*
Y301111D03*
G54D20*
X52607Y168352D03*
X56607D03*
X72800Y183200D03*
X25900Y203600D03*
X65500Y231100D03*
X45938Y232004D03*
X41938D03*
X64100Y184400D03*
X46500Y183500D03*
X50500D03*
X26600Y275500D03*
X27200Y301800D03*
X65500Y372100D03*
X22000Y371652D03*
X43000Y371533D03*
X73100Y372100D03*
X29900Y371652D03*
X50700Y371533D03*
X87300Y223700D03*
X89800Y183400D03*
X85795Y371726D03*
X93695D03*
X89600Y391200D03*
X195161Y128117D03*
X201139Y114695D03*
X156700Y132800D03*
X250791Y65727D03*
X238880Y66862D03*
X220227Y66815D03*
X238900Y284500D03*
X245800Y284600D03*
X219400Y284000D03*
X226600Y284500D03*
X260000D03*
X240200Y303400D03*
X258700Y300900D03*
X222000Y303300D03*
X255500Y415800D03*
X318050Y293200D03*
X267600Y284500D03*
X285400Y317400D03*
X283000Y405800D03*
X269500Y416800D03*
X343000Y302300D03*
X345121Y328050D03*
X370932Y320300D03*
X326083Y409166D03*
X412400Y340384D03*
X437500Y340800D03*
X427700Y340600D03*
X400300Y341700D03*
X469996Y351012D03*
X451400Y340800D03*
X460327Y340801D03*
X464327D03*
X482427Y354974D03*
X486627D03*
X497900Y341900D03*
X502700D03*
X507337Y341863D03*
X478298Y354854D03*
X480700Y340800D03*
X522000Y351450D03*
X512754Y341784D03*
X573570Y460280D03*
X590350Y327050D03*
X618900Y319400D03*
X631800Y319300D03*
X629370Y456630D03*
X586720Y472980D03*
X664301Y31865D03*
X664000Y53800D03*
X643492Y86736D03*
X639392D03*
X682700Y233800D03*
X695600D03*
X695100Y378300D03*
X675831Y392633D03*
X670610Y415430D03*
X675380Y454460D03*
X667900Y443200D03*
X755523Y90115D03*
X751023D03*
X699600Y233800D03*
X743600Y221000D03*
X739500D03*
X734286Y221023D03*
X726656Y228498D03*
X719300Y217500D03*
X759651Y263407D03*
X751470Y307320D03*
X700200Y378300D03*
X763840Y263310D03*
X782800Y324770D03*
G54D11*
X53100Y152000D03*
X27000Y292200D03*
Y287700D03*
X61867Y242333D03*
X41500Y266100D03*
X27300Y318500D03*
Y314000D03*
X57400Y403150D03*
X85600Y194900D03*
X84100Y213800D03*
X160100Y113400D03*
X156600Y122000D03*
X160100Y117700D03*
X255300Y90000D03*
Y95000D03*
X207800Y284000D03*
X296435Y104177D03*
X277300Y321600D03*
X270668Y378200D03*
Y382200D03*
X274769Y373425D03*
X369300Y279500D03*
X362800Y293000D03*
X369300Y275500D03*
X369100Y283900D03*
X349800Y308000D03*
X358300Y340500D03*
X370800Y344500D03*
X361327Y312654D03*
X370982Y328503D03*
X340550Y309823D03*
X326638Y405044D03*
X388949Y340563D03*
X470397Y358638D03*
X527915Y335679D03*
Y331679D03*
X635992Y94236D03*
X629300Y278745D03*
X593800Y346950D03*
X597723Y352729D03*
Y356729D03*
X600587Y322456D03*
Y326656D03*
X622350Y348900D03*
X619850Y353400D03*
X622350Y310491D03*
X619850Y314991D03*
X611850D03*
X612350Y353400D03*
X597373Y378955D03*
Y374955D03*
X617067Y378894D03*
Y374894D03*
X586600Y486650D03*
X581000Y460300D03*
X581070Y468530D03*
X643492Y94236D03*
X668231Y392433D03*
X672800Y407500D03*
X646020Y395300D03*
X743500Y94500D03*
X728531Y98293D03*
X736000Y86200D03*
Y90300D03*
X743500Y86300D03*
Y90400D03*
X757471Y143624D03*
X757450Y139500D03*
X753600Y169550D03*
X758500Y135400D03*
X750408Y154100D03*
X750400Y160050D03*
X750423Y148245D03*
X753602Y173715D03*
X751268Y164081D03*
X753618Y179053D03*
X753630Y197200D03*
X711800Y217500D03*
X753618Y183153D03*
Y187253D03*
X753630Y206200D03*
X747270Y297120D03*
X754183Y317184D03*
X725270Y423930D03*
X728200Y475400D03*
X794770Y307120D03*
Y302620D03*
G54D105*
G01X121778Y-377522D02*
X122652Y-376647D01*
X123307Y-375189D01*
X123744Y-373146D01*
X123307Y-371397D01*
X122434Y-370230D01*
X120905Y-369355D01*
X115010D01*
Y-386855D01*
X122215D01*
X123744Y-385689D01*
X124617Y-383938D01*
X125054Y-381897D01*
X124617Y-379855D01*
X123307Y-378105D01*
X121778Y-377522D01*
X115010D01*
G01X134475Y-386855D02*
Y-375189D01*
G01Y-377522D02*
X135567Y-376355D01*
X136659Y-375480D01*
X138187Y-375189D01*
X139278Y-375480D01*
X140589Y-376355D01*
G01X150447Y-392105D02*
X151757Y-392688D01*
X153504Y-392105D01*
X154595Y-390939D01*
X155469Y-389480D01*
X156778Y-384814D01*
X159617Y-375189D01*
G01X152630D02*
X156778Y-384814D01*
G01X176025Y-376647D02*
X174497Y-375480D01*
X173187Y-375189D01*
X171440Y-375772D01*
X170130Y-376938D01*
X169257Y-378980D01*
X169038Y-381022D01*
X169257Y-383064D01*
X170130Y-384814D01*
X171440Y-386272D01*
X173187Y-386855D01*
X174715Y-386272D01*
X176025Y-385105D01*
G01X186757Y-378980D02*
X193744D01*
X193089Y-376938D01*
X191997Y-375772D01*
X190469Y-375189D01*
X188940Y-375480D01*
X187630Y-376355D01*
X186757Y-378397D01*
X186320Y-380147D01*
Y-381897D01*
X186757Y-383647D01*
X187849Y-385397D01*
X189159Y-386563D01*
X190687Y-386855D01*
X192215Y-386272D01*
X193744Y-384522D01*
G01X229835Y-370814D02*
X228525Y-369938D01*
X226997Y-369355D01*
X225250D01*
X223285Y-370230D01*
X221757Y-371688D01*
X220665Y-373439D01*
X219792Y-376355D01*
X219573Y-378980D01*
X220010Y-381605D01*
X220665Y-383355D01*
X221975Y-385105D01*
X223504Y-386272D01*
X225032Y-386855D01*
X226560D01*
X228089Y-386272D01*
X229399Y-385397D01*
X230491Y-384231D01*
G01X246462Y-386855D02*
Y-375189D01*
G01Y-377230D02*
X245589Y-376064D01*
X244278Y-375480D01*
X242750Y-375189D01*
X241222Y-375772D01*
X239912Y-376938D01*
X239038Y-378688D01*
X238602Y-381022D01*
X239038Y-383355D01*
X239912Y-385105D01*
X241222Y-386272D01*
X242750Y-386855D01*
X244278Y-386563D01*
X245589Y-385689D01*
X246462Y-384522D01*
G01X256320Y-386855D02*
Y-375189D01*
G01Y-378105D02*
X257194Y-376647D01*
X258504Y-375480D01*
X260250Y-375189D01*
X261778Y-375480D01*
X263089Y-376647D01*
X263744Y-378688D01*
Y-386855D01*
G01X272947Y-392105D02*
X274257Y-392688D01*
X276004Y-392105D01*
X277095Y-390939D01*
X277969Y-389480D01*
X279278Y-384814D01*
X282117Y-375189D01*
G01X275130D02*
X279278Y-384814D01*
G01X295032Y-386855D02*
X293722Y-386563D01*
X292412Y-385397D01*
X291538Y-383355D01*
X291102Y-381022D01*
X291538Y-378688D01*
X292412Y-376647D01*
X293722Y-375480D01*
X295032Y-375189D01*
X296342Y-375480D01*
X297652Y-376647D01*
X298525Y-378688D01*
X298744Y-381022D01*
X298525Y-383355D01*
X297652Y-385397D01*
X296342Y-386563D01*
X295032Y-386855D01*
G01X308820D02*
Y-375189D01*
G01Y-378105D02*
X309694Y-376647D01*
X311004Y-375480D01*
X312750Y-375189D01*
X314278Y-375480D01*
X315589Y-376647D01*
X316244Y-378688D01*
Y-386855D01*
G01X342947Y-384522D02*
X344694Y-385980D01*
X346659Y-386855D01*
X348405D01*
X350152Y-385980D01*
X351462Y-384522D01*
X352117Y-382480D01*
X351680Y-380439D01*
X350589Y-378688D01*
X348624Y-377522D01*
X346004Y-376938D01*
X344475Y-375772D01*
X343820Y-373730D01*
X344257Y-371688D01*
X345349Y-370230D01*
X346877Y-369355D01*
X348405D01*
X349934Y-369938D01*
X351244Y-371397D01*
G01X369835Y-370814D02*
X368525Y-369938D01*
X366997Y-369355D01*
X365250D01*
X363285Y-370230D01*
X361757Y-371688D01*
X360665Y-373439D01*
X359792Y-376355D01*
X359573Y-378980D01*
X360010Y-381605D01*
X360665Y-383355D01*
X361975Y-385105D01*
X363504Y-386272D01*
X365032Y-386855D01*
X366560D01*
X368089Y-386272D01*
X369399Y-385397D01*
X370491Y-384231D01*
G01X387335Y-370814D02*
X386025Y-369938D01*
X384497Y-369355D01*
X382750D01*
X380785Y-370230D01*
X379257Y-371688D01*
X378165Y-373439D01*
X377292Y-376355D01*
X377073Y-378980D01*
X377510Y-381605D01*
X378165Y-383355D01*
X379475Y-385105D01*
X381004Y-386272D01*
X382532Y-386855D01*
X384060D01*
X385589Y-386272D01*
X386899Y-385397D01*
X387991Y-384231D01*
G01X210605Y-341855D02*
Y-324355D01*
X216282Y-338938D01*
X221959Y-324355D01*
Y-341855D01*
G01X233782D02*
X232472Y-341563D01*
X231162Y-340397D01*
X230288Y-338355D01*
X229852Y-336022D01*
X230288Y-333688D01*
X231162Y-331647D01*
X232472Y-330480D01*
X233782Y-330189D01*
X235092Y-330480D01*
X236402Y-331647D01*
X237275Y-333688D01*
X237494Y-336022D01*
X237275Y-338355D01*
X236402Y-340397D01*
X235092Y-341563D01*
X233782Y-341855D01*
G01X255212Y-324355D02*
Y-341855D01*
G01Y-339231D02*
X254339Y-340689D01*
X253028Y-341563D01*
X251500Y-341855D01*
X249754Y-341272D01*
X248444Y-339814D01*
X247570Y-338064D01*
X247352Y-336022D01*
X247570Y-333980D01*
X248444Y-332230D01*
X249754Y-330772D01*
X251500Y-330189D01*
X253028Y-330480D01*
X254120Y-331064D01*
X255212Y-332230D01*
G01X265507Y-333980D02*
X272494D01*
X271839Y-331938D01*
X270747Y-330772D01*
X269219Y-330189D01*
X267690Y-330480D01*
X266380Y-331355D01*
X265507Y-333397D01*
X265070Y-335147D01*
Y-336897D01*
X265507Y-338647D01*
X266599Y-340397D01*
X267909Y-341563D01*
X269437Y-341855D01*
X270965Y-341272D01*
X272494Y-339522D01*
G01X286282Y-341855D02*
Y-324355D01*
G01X566882Y-386855D02*
Y-369355D01*
X564262Y-372855D01*
G01Y-386855D02*
X569502D01*
G01X580234Y-379564D02*
X581762Y-377522D01*
X583072Y-376355D01*
X584819Y-375772D01*
X586347Y-376355D01*
X587439Y-377522D01*
X588312Y-379272D01*
X588530Y-381313D01*
X588312Y-383064D01*
X587439Y-384814D01*
X586128Y-386272D01*
X584600Y-386855D01*
X582854Y-386272D01*
X581325Y-384522D01*
X580452Y-381897D01*
X580234Y-378980D01*
X580670Y-375189D01*
X581325Y-373146D01*
X582417Y-371105D01*
X583945Y-369647D01*
X585474Y-369355D01*
X587002Y-369938D01*
X588094Y-371397D01*
G01X597079Y-383355D02*
X598388Y-385397D01*
X600135Y-386563D01*
X602100Y-386855D01*
X603847Y-386563D01*
X605594Y-385105D01*
X606685Y-383355D01*
X606904Y-381605D01*
X606467Y-379564D01*
X604939Y-378105D01*
X603410Y-377522D01*
X601445D01*
G01X603410D02*
X604720Y-376647D01*
X605812Y-375189D01*
X606249Y-373439D01*
X605812Y-371688D01*
X604720Y-370230D01*
X602755Y-369355D01*
X600790Y-369647D01*
X598825Y-370814D01*
G01X619382Y-386855D02*
Y-369355D01*
X616762Y-372855D01*
G01Y-386855D02*
X622002D01*
G01X632734Y-379564D02*
X634262Y-377522D01*
X635572Y-376355D01*
X637319Y-375772D01*
X638847Y-376355D01*
X639939Y-377522D01*
X640812Y-379272D01*
X641030Y-381313D01*
X640812Y-383064D01*
X639939Y-384814D01*
X638628Y-386272D01*
X637100Y-386855D01*
X635354Y-386272D01*
X633825Y-384522D01*
X632952Y-381897D01*
X632734Y-378980D01*
X633170Y-375189D01*
X633825Y-373146D01*
X634917Y-371105D01*
X636445Y-369647D01*
X637974Y-369355D01*
X639502Y-369938D01*
X640594Y-371397D01*
G01X553765Y-341855D02*
Y-324355D01*
X559005D01*
X560752Y-325230D01*
X562062Y-327272D01*
X562499Y-329605D01*
X562062Y-331938D01*
X560970Y-333688D01*
X559005Y-334564D01*
X553765D01*
G01X580435Y-325814D02*
X579125Y-324938D01*
X577597Y-324355D01*
X575850D01*
X573885Y-325230D01*
X572357Y-326688D01*
X571265Y-328439D01*
X570392Y-331355D01*
X570173Y-333980D01*
X570610Y-336605D01*
X571265Y-338355D01*
X572575Y-340105D01*
X574104Y-341272D01*
X575632Y-341855D01*
X577160D01*
X578689Y-341272D01*
X579999Y-340397D01*
X581091Y-339231D01*
G01X594878Y-332522D02*
X595752Y-331647D01*
X596407Y-330189D01*
X596844Y-328146D01*
X596407Y-326397D01*
X595534Y-325230D01*
X594005Y-324355D01*
X588110D01*
Y-341855D01*
X595315D01*
X596844Y-340689D01*
X597717Y-338938D01*
X598154Y-336897D01*
X597717Y-334855D01*
X596407Y-333105D01*
X594878Y-332522D01*
X588110D01*
G01X604082Y-347688D02*
X617182D01*
G01X623110Y-341855D02*
Y-324355D01*
X633154Y-341855D01*
Y-324355D01*
G01X645632Y-341855D02*
X643885Y-341563D01*
X642357Y-340397D01*
X641047Y-338647D01*
X640173Y-336605D01*
X639737Y-334272D01*
Y-331938D01*
X640173Y-329605D01*
X641047Y-327563D01*
X642357Y-325814D01*
X643885Y-324647D01*
X645632Y-324355D01*
X647378Y-324647D01*
X648907Y-325814D01*
X650217Y-327563D01*
X651091Y-329605D01*
X651527Y-331938D01*
Y-334272D01*
X651091Y-336605D01*
X650217Y-338647D01*
X648907Y-340397D01*
X647378Y-341563D01*
X645632Y-341855D01*
G01X696473Y-324355D02*
X701932Y-341855D01*
X707391Y-324355D01*
G01X723799Y-341855D02*
X715065D01*
Y-324355D01*
X723799D01*
G01X720305Y-332813D02*
X715065D01*
G01X732565Y-341855D02*
Y-324355D01*
X738024D01*
X739770Y-325230D01*
X740862Y-326397D01*
X741299Y-328730D01*
X740862Y-331064D01*
X739552Y-332522D01*
X738024Y-333397D01*
X732565D01*
G01X738024D02*
X741299Y-341855D01*
G01X754432Y-342438D02*
X753995Y-342147D01*
Y-341563D01*
X754432Y-341272D01*
X754869Y-341563D01*
Y-342147D01*
X754432Y-342438D01*
G01X728182Y-386855D02*
Y-369355D01*
X725562Y-372855D01*
G01Y-386855D02*
X730802D01*
G01X843132Y-369355D02*
Y-386855D01*
G01X838110Y-369355D02*
X848154D01*
G01X856047Y-384522D02*
X857794Y-385980D01*
X859759Y-386855D01*
X861505D01*
X863252Y-385980D01*
X864562Y-384522D01*
X865217Y-382480D01*
X864780Y-380439D01*
X863689Y-378688D01*
X861724Y-377522D01*
X859104Y-376938D01*
X857575Y-375772D01*
X856920Y-373730D01*
X857357Y-371688D01*
X858449Y-370230D01*
X859977Y-369355D01*
X861505D01*
X863034Y-369938D01*
X864344Y-371397D01*
G01X872455Y-386855D02*
Y-369355D01*
X878132Y-383938D01*
X883809Y-369355D01*
Y-386855D01*
G01X890829D02*
Y-369355D01*
X895195D01*
X896942Y-370230D01*
X898252Y-371397D01*
X899344Y-373146D01*
X900217Y-375189D01*
X900435Y-378105D01*
X900217Y-381022D01*
X899344Y-383064D01*
X898252Y-384814D01*
X896942Y-385980D01*
X895195Y-386855D01*
X890829D01*
G01X830015Y-324355D02*
Y-341855D01*
X838749D01*
G01X855812D02*
Y-330189D01*
G01Y-332230D02*
X854939Y-331064D01*
X853628Y-330480D01*
X852100Y-330189D01*
X850572Y-330772D01*
X849262Y-331938D01*
X848388Y-333688D01*
X847952Y-336022D01*
X848388Y-338355D01*
X849262Y-340105D01*
X850572Y-341272D01*
X852100Y-341855D01*
X853628Y-341563D01*
X854939Y-340689D01*
X855812Y-339522D01*
G01X864797Y-347105D02*
X866107Y-347688D01*
X867854Y-347105D01*
X868945Y-345939D01*
X869819Y-344480D01*
X871128Y-339814D01*
X873967Y-330189D01*
G01X866980D02*
X871128Y-339814D01*
G01X883607Y-333980D02*
X890594D01*
X889939Y-331938D01*
X888847Y-330772D01*
X887319Y-330189D01*
X885790Y-330480D01*
X884480Y-331355D01*
X883607Y-333397D01*
X883170Y-335147D01*
Y-336897D01*
X883607Y-338647D01*
X884699Y-340397D01*
X886009Y-341563D01*
X887537Y-341855D01*
X889065Y-341272D01*
X890594Y-339522D01*
G01X901325Y-341855D02*
Y-330189D01*
G01Y-332522D02*
X902417Y-331355D01*
X903509Y-330480D01*
X905037Y-330189D01*
X906128Y-330480D01*
X907439Y-331355D01*
G01X994432Y-386855D02*
X992685Y-386563D01*
X991157Y-385397D01*
X989847Y-383647D01*
X988973Y-381605D01*
X988537Y-379272D01*
Y-376938D01*
X988973Y-374605D01*
X989847Y-372563D01*
X991157Y-370814D01*
X992685Y-369647D01*
X994432Y-369355D01*
X996178Y-369647D01*
X997707Y-370814D01*
X999017Y-372563D01*
X999891Y-374605D01*
X1000327Y-376938D01*
Y-379272D01*
X999891Y-381605D01*
X999017Y-383647D01*
X997707Y-385397D01*
X996178Y-386563D01*
X994432Y-386855D01*
G01X996178Y-382188D02*
X998799Y-386855D01*
G01X1007129Y-369355D02*
Y-381897D01*
X1008002Y-384522D01*
X1009749Y-386272D01*
X1011932Y-386855D01*
X1014115Y-386272D01*
X1015862Y-384522D01*
X1016735Y-381897D01*
Y-369355D01*
G01X1026812D02*
X1032052D01*
G01X1029432D02*
Y-386855D01*
G01X1026812D02*
X1032052D01*
G01X1041910D02*
Y-369355D01*
X1051954Y-386855D01*
Y-369355D01*
G01X1069235Y-370814D02*
X1067925Y-369938D01*
X1066397Y-369355D01*
X1064650D01*
X1062685Y-370230D01*
X1061157Y-371688D01*
X1060065Y-373439D01*
X1059192Y-376355D01*
X1058973Y-378980D01*
X1059410Y-381605D01*
X1060065Y-383355D01*
X1061375Y-385105D01*
X1062904Y-386272D01*
X1064432Y-386855D01*
X1065960D01*
X1067489Y-386272D01*
X1068799Y-385397D01*
X1069891Y-384231D01*
G01X1081932Y-386855D02*
Y-378980D01*
X1077565Y-369355D01*
G01X1086299D02*
X1081932Y-378980D01*
G01X972129Y-341855D02*
Y-324355D01*
X976495D01*
X978242Y-325230D01*
X979552Y-326397D01*
X980644Y-328146D01*
X981517Y-330189D01*
X981735Y-333105D01*
X981517Y-336022D01*
X980644Y-338064D01*
X979552Y-339814D01*
X978242Y-340980D01*
X976495Y-341855D01*
X972129D01*
G01X991157Y-333980D02*
X998144D01*
X997489Y-331938D01*
X996397Y-330772D01*
X994869Y-330189D01*
X993340Y-330480D01*
X992030Y-331355D01*
X991157Y-333397D01*
X990720Y-335147D01*
Y-336897D01*
X991157Y-338647D01*
X992249Y-340397D01*
X993559Y-341563D01*
X995087Y-341855D01*
X996615Y-341272D01*
X998144Y-339522D01*
G01X1008657Y-339814D02*
X1009749Y-340980D01*
X1011277Y-341855D01*
X1012587D01*
X1013897Y-341272D01*
X1014770Y-340397D01*
X1015207Y-339231D01*
X1014989Y-337480D01*
X1014115Y-336605D01*
X1010185Y-334855D01*
X1009312Y-332813D01*
X1009749Y-331355D01*
X1010622Y-330480D01*
X1011932Y-330189D01*
X1013242Y-330480D01*
X1014552Y-331355D01*
G01X1029432Y-330189D02*
Y-341855D01*
G01Y-325522D02*
X1028995Y-325230D01*
Y-324647D01*
X1029432Y-324355D01*
X1029869Y-324647D01*
Y-325230D01*
X1029432Y-325522D01*
G01X1043875Y-346230D02*
X1045404Y-347397D01*
X1047150Y-347688D01*
X1048678Y-347397D01*
X1049989Y-345939D01*
X1050862Y-343897D01*
Y-330189D01*
G01Y-332522D02*
X1049989Y-331355D01*
X1048678Y-330480D01*
X1047150Y-330189D01*
X1045404Y-330772D01*
X1044312Y-331938D01*
X1043438Y-333980D01*
X1043002Y-336022D01*
X1043220Y-337772D01*
X1044094Y-339814D01*
X1045404Y-341272D01*
X1047150Y-341855D01*
X1048460Y-341563D01*
X1049989Y-340397D01*
X1050862Y-339231D01*
G01X1060720Y-341855D02*
Y-330189D01*
G01Y-333105D02*
X1061594Y-331647D01*
X1062904Y-330480D01*
X1064650Y-330189D01*
X1066178Y-330480D01*
X1067489Y-331647D01*
X1068144Y-333688D01*
Y-341855D01*
G01X1078657Y-333980D02*
X1085644D01*
X1084989Y-331938D01*
X1083897Y-330772D01*
X1082369Y-330189D01*
X1080840Y-330480D01*
X1079530Y-331355D01*
X1078657Y-333397D01*
X1078220Y-335147D01*
Y-336897D01*
X1078657Y-338647D01*
X1079749Y-340397D01*
X1081059Y-341563D01*
X1082587Y-341855D01*
X1084115Y-341272D01*
X1085644Y-339522D01*
G01X1096375Y-341855D02*
Y-330189D01*
G01Y-332522D02*
X1097467Y-331355D01*
X1098559Y-330480D01*
X1100087Y-330189D01*
X1101178Y-330480D01*
X1102489Y-331355D01*
G01X1143132Y-369355D02*
X1141385Y-369938D01*
X1140075Y-371397D01*
X1139202Y-373146D01*
X1138547Y-375480D01*
X1138329Y-378105D01*
X1138547Y-380730D01*
X1139202Y-383064D01*
X1140075Y-384814D01*
X1141385Y-386272D01*
X1143132Y-386855D01*
X1144878Y-386272D01*
X1146189Y-384814D01*
X1147062Y-383064D01*
X1147717Y-380730D01*
X1147935Y-378105D01*
X1147717Y-375480D01*
X1147062Y-373146D01*
X1146189Y-371397D01*
X1144878Y-369938D01*
X1143132Y-369355D01*
G01X1156484Y-379564D02*
X1158012Y-377522D01*
X1159322Y-376355D01*
X1161069Y-375772D01*
X1162597Y-376355D01*
X1163689Y-377522D01*
X1164562Y-379272D01*
X1164780Y-381313D01*
X1164562Y-383064D01*
X1163689Y-384814D01*
X1162378Y-386272D01*
X1160850Y-386855D01*
X1159104Y-386272D01*
X1157575Y-384522D01*
X1156702Y-381897D01*
X1156484Y-378980D01*
X1156920Y-375189D01*
X1157575Y-373146D01*
X1158667Y-371105D01*
X1160195Y-369647D01*
X1161724Y-369355D01*
X1163252Y-369938D01*
X1164344Y-371397D01*
G01X1174202Y-387438D02*
X1182062Y-369355D01*
G01X1191484Y-372272D02*
X1192794Y-370522D01*
X1194322Y-369647D01*
X1196069Y-369355D01*
X1198252Y-369938D01*
X1199780Y-371397D01*
X1200217Y-373146D01*
X1199999Y-374897D01*
X1199125Y-376355D01*
X1194759Y-379272D01*
X1192794Y-381313D01*
X1191484Y-384231D01*
X1191047Y-386855D01*
X1200217D01*
G01X1213132D02*
Y-369355D01*
X1210512Y-372855D01*
G01Y-386855D02*
X1215752D01*
G01X1226702Y-387438D02*
X1234562Y-369355D01*
G01X1243984Y-372272D02*
X1245294Y-370522D01*
X1246822Y-369647D01*
X1248569Y-369355D01*
X1250752Y-369938D01*
X1252280Y-371397D01*
X1252717Y-373146D01*
X1252499Y-374897D01*
X1251625Y-376355D01*
X1247259Y-379272D01*
X1245294Y-381313D01*
X1243984Y-384231D01*
X1243547Y-386855D01*
X1252717D01*
G01X1265632Y-369355D02*
X1263885Y-369938D01*
X1262575Y-371397D01*
X1261702Y-373146D01*
X1261047Y-375480D01*
X1260829Y-378105D01*
X1261047Y-380730D01*
X1261702Y-383064D01*
X1262575Y-384814D01*
X1263885Y-386272D01*
X1265632Y-386855D01*
X1267378Y-386272D01*
X1268689Y-384814D01*
X1269562Y-383064D01*
X1270217Y-380730D01*
X1270435Y-378105D01*
X1270217Y-375480D01*
X1269562Y-373146D01*
X1268689Y-371397D01*
X1267378Y-369938D01*
X1265632Y-369355D01*
G01X1283132Y-386855D02*
Y-369355D01*
X1280512Y-372855D01*
G01Y-386855D02*
X1285752D01*
G01X1300195D02*
X1300632Y-383064D01*
X1301287Y-379855D01*
X1302160Y-376938D01*
X1303252Y-373730D01*
X1304999Y-369355D01*
X1296265D01*
G01X1190829Y-341855D02*
Y-324355D01*
X1195195D01*
X1196942Y-325230D01*
X1198252Y-326397D01*
X1199344Y-328146D01*
X1200217Y-330189D01*
X1200435Y-333105D01*
X1200217Y-336022D01*
X1199344Y-338064D01*
X1198252Y-339814D01*
X1196942Y-340980D01*
X1195195Y-341855D01*
X1190829D01*
G01X1217062D02*
Y-330189D01*
G01Y-332230D02*
X1216189Y-331064D01*
X1214878Y-330480D01*
X1213350Y-330189D01*
X1211822Y-330772D01*
X1210512Y-331938D01*
X1209638Y-333688D01*
X1209202Y-336022D01*
X1209638Y-338355D01*
X1210512Y-340105D01*
X1211822Y-341272D01*
X1213350Y-341855D01*
X1214878Y-341563D01*
X1216189Y-340689D01*
X1217062Y-339522D01*
G01X1230632Y-324355D02*
Y-341855D01*
G01X1227575Y-330189D02*
X1233689D01*
G01X1244857Y-333980D02*
X1251844D01*
X1251189Y-331938D01*
X1250097Y-330772D01*
X1248569Y-330189D01*
X1247040Y-330480D01*
X1245730Y-331355D01*
X1244857Y-333397D01*
X1244420Y-335147D01*
Y-336897D01*
X1244857Y-338647D01*
X1245949Y-340397D01*
X1247259Y-341563D01*
X1248787Y-341855D01*
X1250315Y-341272D01*
X1251844Y-339522D01*
G01X20103Y-86244D02*
G03I-4291J0D01*
G01X0Y-87362D02*
G03X15000Y-102362I15000J0D01*
G01X0Y-11811D02*
Y-87362D01*
G01X3937Y-7874D02*
G03X0Y-11811I0J-3937D01*
G01X15748Y-7874D02*
X3937D01*
G01X0Y7874D02*
G03X7874Y0I7874J0D01*
G01X818897D02*
X7874D01*
G01X0Y7874D02*
Y562992D01*
G01X7874Y570866D02*
G03X0Y562992I0J-7874D01*
G01X7874Y570866D02*
X326781D01*
G01X312004Y-102362D02*
X15000D01*
G01X46456Y0D02*
G03Y-7874I0J-3937D01*
G01X15748D02*
G03Y0I0J3937D01*
G01X287400Y-7874D02*
X46456D01*
G01X40452Y499724D02*
G03I-3051J0D01*
G01X41535Y535157D02*
G03I-4134J0D01*
G01X44685Y517441D02*
G03I-7284J0D01*
G01X121082Y39055D02*
G03I-5019J0D01*
G01X120807Y14567D02*
G03I-4744J0D01*
G01X319878Y-102362D02*
G03X312004I-3937J0D01*
G01X811771D02*
X319878D01*
G01X326770Y0D02*
G03Y-7874I0J-3937D01*
G01X287400D02*
G03Y0I0J3937D01*
G01X302165Y531496D02*
G03I-6890J0D01*
G01X597707Y-7874D02*
X326770D01*
G01X379921Y156220D02*
G03I-5906J0D01*
G01X342529Y530315D02*
G03X334655I-3937J0D01*
G01X342529Y520720D02*
G03X352474Y509057I11811J0D01*
G01X334655Y520720D02*
G03X351230Y501282I19685J0D01*
G01X384484Y503937D02*
X352475Y509057D01*
G01X383858Y496063D02*
X351231Y501282D01*
G01X442287Y503937D02*
X384484D01*
G01X442913Y496063D02*
X383858D01*
G01X342529Y530315D02*
Y520720D01*
G01X334655Y562992D02*
Y520720D01*
G01X346466Y570866D02*
G03X342529Y566929I0J-3937D01*
G01X334655Y555512D02*
G03X342529I3937J0D01*
G01X346466Y570866D02*
X480325D01*
G01X334655Y562992D02*
G03X326781Y570866I-7874J0D01*
G01X342529Y566929D02*
Y555512D01*
G01X415943Y539991D02*
G03I-4291J0D01*
G01X474316Y509060D02*
X442287Y503937D01*
G01X475560Y501285D02*
X442913Y496063D01*
G01X492136Y530315D02*
G03X484262I-3937J0D01*
G01X474316Y509060D02*
G03X484262Y520723I-1865J11663D01*
G01X475560Y501285D02*
G03X492136Y520723I-3109J19438D01*
G01X484262Y530315D02*
Y520723D01*
G01X492136Y562992D02*
Y520723D01*
G01X484262Y566929D02*
G03X480325Y570866I-3937J0D01*
G01X484262Y555512D02*
G03X492136I3937J0D01*
G01X500010Y570866D02*
G03X492136Y562992I0J-7874D01*
G01X500010Y570866D02*
X818897D01*
G01X484262Y566929D02*
Y555512D01*
G01X537401Y371299D02*
G03I-5905J0D01*
G01X538386Y531496D02*
G03I-6890J0D01*
G01X628416Y0D02*
G03Y-7874I0J-3937D01*
G01X597707D02*
G03Y0I0J3937D01*
G01X780315Y-7874D02*
X628416D01*
G01X602362Y116141D02*
G03I-5906J0D01*
G01X817003Y-86834D02*
G03I-4292J0D01*
G01X811771Y-102362D02*
G03X826771Y-87362I0J15000D01*
G01X811023Y0D02*
G03Y-7874I0J-3937D01*
G01X780315D02*
G03Y0I0J3937D01*
G01X822834Y-7874D02*
X811023D01*
G01X818897Y0D02*
G03X826771Y7874I0J7874D01*
G01X818897Y0D02*
X807086D01*
G01X787401Y198819D02*
G03I-5905J0D01*
G01X792421Y499724D02*
G03I-3051J0D01*
G01X793504Y535157D02*
G03I-4134J0D01*
G01X796653Y517441D02*
G03I-7283J0D01*
G01X826771Y562992D02*
G03X818897Y570866I-7874J0D01*
G01X826771Y-11811D02*
Y-87362D01*
G01Y-11811D02*
G03X822834Y-7874I-3937J0D01*
G01X826771Y562992D02*
Y7874D01*
G54D30*
X56541Y234486D03*
X75500Y234500D03*
X33700Y226900D03*
X76800Y186600D03*
X29900Y207000D03*
X70500Y234500D03*
X52400D03*
X32405Y187717D03*
X36405D03*
X30700Y278900D03*
X31400Y305200D03*
X25700Y391900D03*
X77200Y370500D03*
X38200Y370300D03*
X34100D03*
X60400Y370100D03*
X54800D03*
X25700Y399400D03*
X37500Y387400D03*
X85700Y186800D03*
X91300Y227100D03*
X93700Y394600D03*
X81300Y370500D03*
X98295Y370293D03*
X102395D03*
X246530Y70236D03*
X252000Y287900D03*
X230700D03*
X256000D03*
X234800Y287800D03*
X215300Y287400D03*
X271600Y287900D03*
X275600D03*
X294708Y295526D03*
X287214Y291617D03*
X323900Y251200D03*
X265250Y374150D03*
X279000Y401700D03*
X348597Y213040D03*
X365387Y261409D03*
X372119Y261280D03*
X384000Y344450D03*
X330531Y412561D03*
X416841Y343784D03*
X447300Y344200D03*
X472296D03*
X506200Y355700D03*
X499700D03*
X493200D03*
X476500Y344200D03*
X532894Y351015D03*
X528894D03*
X535336Y335222D03*
X541714Y335203D03*
X547315Y335188D03*
X551394D03*
X518000Y354850D03*
X514000Y355000D03*
X613211Y283605D03*
X608711D03*
X617000Y476200D03*
X621500D03*
X667353Y230332D03*
X641579Y230590D03*
X658610Y230375D03*
X663110D03*
X654464Y230515D03*
X650287Y230474D03*
X645968Y230497D03*
X691100Y237200D03*
X686900D03*
X678500D03*
X654770Y398060D03*
X658840D03*
X687581Y395833D03*
X686390Y428270D03*
X695380Y428250D03*
X731900Y92000D03*
X730712Y231907D03*
X738786Y231923D03*
X725750Y220972D03*
X712720Y237822D03*
X746970Y310720D03*
X700200Y394700D03*
X710200Y437930D03*
X717150Y453695D03*
X706120Y437930D03*
X743480Y435590D03*
X801934Y291146D03*
G54D21*
X49200Y142500D03*
X44200D03*
X39200D03*
X34200D03*
G54D12*
X56500Y152000D03*
X30400Y292200D03*
Y287700D03*
X65267Y242333D03*
X44900Y266100D03*
X30700Y318500D03*
Y314000D03*
X60800Y403150D03*
X89000Y194900D03*
X87500Y213800D03*
X163500Y113400D03*
X160000Y122000D03*
X163500Y117700D03*
X258700Y90000D03*
Y95000D03*
X211200Y284000D03*
X299835Y104177D03*
X280700Y321600D03*
X274068Y378200D03*
Y382200D03*
X278169Y373425D03*
X372700Y279500D03*
X366200Y293000D03*
X372700Y275500D03*
X372500Y283900D03*
X353200Y308000D03*
X361700Y340500D03*
X374200Y344500D03*
X364727Y312654D03*
X374382Y328503D03*
X343950Y309823D03*
X330038Y405044D03*
X392349Y340563D03*
X473797Y358638D03*
X531315Y335679D03*
Y331679D03*
X632700Y278745D03*
X597200Y346950D03*
X601123Y352729D03*
Y356729D03*
X603987Y322456D03*
Y326656D03*
X625750Y348900D03*
X623250Y353400D03*
X625750Y310491D03*
X623250Y314991D03*
X615250D03*
X615750Y353400D03*
X600773Y378955D03*
Y374955D03*
X620467Y378894D03*
Y374894D03*
X590000Y486650D03*
X584400Y460300D03*
X584470Y468530D03*
X646892Y94236D03*
X639392D03*
X671631Y392433D03*
X676200Y407500D03*
X649420Y395300D03*
X746900Y94500D03*
X731931Y98293D03*
X739400Y86200D03*
Y90300D03*
X746900Y86300D03*
Y90400D03*
X757000Y169550D03*
X753808Y154100D03*
X753800Y160050D03*
X753823Y148245D03*
X757002Y173715D03*
X754668Y164081D03*
X757018Y179053D03*
X757030Y197200D03*
X715200Y217500D03*
X757018Y183153D03*
Y187253D03*
X757030Y206200D03*
X750670Y297120D03*
X757583Y317184D03*
X728670Y423930D03*
X731600Y475400D03*
X760871Y143624D03*
X760850Y139500D03*
X761900Y135400D03*
X798170Y307120D03*
Y302620D03*
G54D13*
X31000Y165500D03*
X29600Y227500D03*
Y223500D03*
X30400Y283200D03*
Y296700D03*
X44900Y261900D03*
X30700Y323000D03*
Y309500D03*
X77200Y314000D03*
X68750Y367751D03*
X26050Y367552D03*
X47100Y367400D03*
X87500Y217900D03*
X89000Y190900D03*
X77496Y281695D03*
Y276695D03*
Y286695D03*
X77400Y309500D03*
Y304500D03*
X89845Y367626D03*
X163970Y104310D03*
X187000Y110000D03*
X179500D03*
X163500Y109050D03*
X173500Y114500D03*
X196813Y114644D03*
X233700Y68000D03*
X231200Y73000D03*
X203700Y298800D03*
Y306800D03*
X257891Y371827D03*
X263200Y412100D03*
Y420300D03*
X259450Y426500D03*
X277700Y42500D03*
Y38000D03*
Y33500D03*
Y29000D03*
X286941Y278576D03*
X301410Y281122D03*
X281906Y297434D03*
X294900Y321700D03*
X372500Y288000D03*
X366200Y299200D03*
X374200D03*
Y340500D03*
X366200Y303200D03*
X374200D03*
X345091Y319717D03*
X345100Y323900D03*
X332386Y443510D03*
X433914Y356373D03*
X481700Y362400D03*
X477600Y350800D03*
X481700Y366800D03*
X625700Y162500D03*
X600737Y280017D03*
X625200Y278745D03*
X630528Y364424D03*
Y385304D03*
X601040Y395220D03*
X612350D03*
X629770Y468430D03*
X629323Y477831D03*
X594400Y479100D03*
X595390Y430440D03*
X668381Y400183D03*
X685800Y440950D03*
X686700Y433300D03*
X754400Y97800D03*
X757030Y201700D03*
Y214200D03*
Y210200D03*
X757583Y321684D03*
X750670Y301620D03*
X735442Y447367D03*
X727790Y447430D03*
X718050Y446230D03*
X766000Y164200D03*
X775436Y293180D03*
X783340D03*
G54D22*
X76600Y134220D03*
Y120380D03*
G54D40*
X74100Y291700D03*
X71800Y318200D03*
X46700Y387500D03*
X95850Y452650D03*
X222200Y95000D03*
X241700D03*
X239000Y279700D03*
X231800Y316900D03*
X250175Y316967D03*
X214400Y317000D03*
X269565Y317151D03*
X291300Y328300D03*
X356500Y334000D03*
X626200Y166500D03*
X629200Y299091D03*
Y288745D03*
Y337500D03*
Y327654D03*
X622770Y369320D03*
X623470Y389940D03*
X586550Y482900D03*
X595700Y434500D03*
X689935Y441196D03*
X714100Y489400D03*
G54D31*
X68400Y182100D03*
X81300Y182200D03*
X169800Y144200D03*
X208100Y162100D03*
X296500Y138700D03*
X297000Y222550D03*
X296500Y180500D03*
X283100Y418600D03*
X566500Y392700D03*
X624770Y455430D03*
X615870Y433930D03*
X620600Y433900D03*
X681900Y321800D03*
X681540Y419660D03*
X686300Y365500D03*
X672800Y442600D03*
G54D14*
X27600Y165500D03*
X26200Y227500D03*
Y223500D03*
X74096Y281695D03*
Y276695D03*
Y286695D03*
X27000Y283200D03*
Y296700D03*
X41500Y261900D03*
X27300Y323000D03*
Y309500D03*
X73800Y314000D03*
X74000Y309500D03*
Y304500D03*
X65350Y367751D03*
X22650Y367552D03*
X43700Y367400D03*
X84100Y217900D03*
X85600Y190900D03*
X86445Y367626D03*
X160570Y104310D03*
X183600Y110000D03*
X176100D03*
X160100Y109050D03*
X170100Y114500D03*
X193413Y114644D03*
X200300Y298800D03*
Y306800D03*
X230300Y68000D03*
X227800Y73000D03*
X254491Y371827D03*
X259800Y412100D03*
Y420300D03*
X256050Y426500D03*
X274300Y42500D03*
Y38000D03*
Y33500D03*
Y29000D03*
X283541Y278576D03*
X298010Y281122D03*
X278506Y297434D03*
X291500Y321700D03*
X369100Y288000D03*
X362800Y299200D03*
X370800D03*
Y340500D03*
X362800Y303200D03*
X370800D03*
X341691Y319717D03*
X341700Y323900D03*
X328986Y443510D03*
X430514Y356373D03*
X478300Y362400D03*
X474200Y350800D03*
X478300Y366800D03*
X622300Y162500D03*
X597337Y280017D03*
X621800Y278745D03*
X627128Y364424D03*
Y385304D03*
X597640Y395220D03*
X608950D03*
X626370Y468430D03*
X625923Y477831D03*
X591000Y479100D03*
X591990Y430440D03*
X664981Y400183D03*
X682400Y440950D03*
X683300Y433300D03*
X751000Y97800D03*
X753630Y201700D03*
Y214200D03*
Y210200D03*
X754183Y321684D03*
X747270Y301620D03*
X732042Y447367D03*
X724390Y447430D03*
X714650Y446230D03*
X762600Y164200D03*
X772036Y293180D03*
X779940D03*
G54D50*
X125850Y183400D03*
X141350D03*
X644681Y314583D03*
X660181D03*
G54D23*
X33000Y159300D03*
Y151700D03*
X89433Y125588D03*
Y117988D03*
X104930Y125610D03*
Y118010D03*
X97230Y125620D03*
Y118020D03*
X153300Y174700D03*
Y167100D03*
X161300Y174700D03*
Y167100D03*
X169300Y174700D03*
Y167100D03*
X141200Y192000D03*
Y199600D03*
X148900Y192000D03*
Y199600D03*
X156700Y192000D03*
Y199600D03*
X172300Y192000D03*
Y199600D03*
X164400Y192000D03*
Y199600D03*
X210500Y206400D03*
Y198800D03*
X243300Y354900D03*
Y362500D03*
X239125Y481261D03*
X231125D03*
X247125D03*
X239125Y488861D03*
X231125D03*
X247125D03*
X560000Y392200D03*
Y399800D03*
X545206Y416682D03*
Y409082D03*
X553206Y416682D03*
Y409082D03*
X561706Y416682D03*
Y409082D03*
X626900Y441200D03*
Y433600D03*
X606000Y438800D03*
Y431200D03*
X635000Y433700D03*
Y441300D03*
X688200Y321700D03*
Y329300D03*
X696305Y329202D03*
Y321602D03*
X667617Y352167D03*
Y359767D03*
X646600Y372200D03*
Y364600D03*
X704805Y329202D03*
Y321602D03*
G54D32*
X68400Y187700D03*
X81300Y187800D03*
X169800Y149800D03*
X208100Y167700D03*
X296500Y144300D03*
X297000Y228150D03*
X296500Y186100D03*
X283100Y424200D03*
X566500Y398300D03*
X624770Y461030D03*
X615870Y439530D03*
X620600Y439500D03*
X681900Y327400D03*
X686300Y371100D03*
X672800Y448200D03*
X681540Y425260D03*
G54D41*
X28150Y265800D03*
X35650Y261925D03*
Y269675D03*
G54D15*
X56507Y175552D03*
X75400Y221000D03*
X34900Y211900D03*
X36249Y191548D03*
X50300Y190700D03*
X75400Y321700D03*
X74200Y338000D03*
X31500Y337800D03*
X52500Y337600D03*
X60900Y391050D03*
X60880Y399390D03*
X95295Y337793D03*
X181100Y114500D03*
X197013Y118544D03*
X204694Y209985D03*
X252645Y279732D03*
X211200Y287800D03*
X221800Y484000D03*
X279126Y278333D03*
X280700Y328400D03*
X354300Y347500D03*
X332508Y439668D03*
X539300Y418400D03*
X621800Y166500D03*
X600837Y284017D03*
X625300Y288745D03*
X597300Y334350D03*
X625300Y327654D03*
X597300Y337900D03*
X595470Y426720D03*
X590100Y490400D03*
X669083Y347018D03*
X671767Y396181D03*
X753908Y280164D03*
X731700Y463900D03*
X739120Y427980D03*
G54D33*
X59800Y188700D03*
X82600Y228300D03*
X176500Y175400D03*
X178500Y198800D03*
X297000Y164800D03*
X296500Y205900D03*
Y247950D03*
X569070Y466030D03*
X581000Y398300D03*
X695700Y395850D03*
X647623Y384089D03*
X642907D03*
X715800Y387400D03*
X736400Y462200D03*
G54D60*
X185789Y188000D03*
G54D24*
X33100Y171500D03*
X25500D03*
X34100Y217500D03*
X26500D03*
X63626Y250139D03*
X56026D03*
X183498Y145380D03*
X191098D03*
X236000Y362400D03*
X228400D03*
X236000Y370100D03*
X228400D03*
X236000Y377800D03*
X228400D03*
X234300Y394954D03*
X226700D03*
X223800Y478500D03*
X216200D03*
X223800Y470500D03*
X216200D03*
X281300Y147500D03*
X273700D03*
X281300Y156500D03*
X273700D03*
X281300Y239500D03*
X273700D03*
X281300Y198000D03*
X273700D03*
X281300Y231000D03*
X273700D03*
X281300Y189500D03*
X273700D03*
X540800Y423900D03*
X533200D03*
X540800Y431500D03*
X533200D03*
X647600Y354400D03*
X655200D03*
X647600Y346700D03*
X655200D03*
X647600Y339000D03*
X655200D03*
X647623Y331307D03*
X655223D03*
X647623Y323624D03*
X655223D03*
X695100Y483400D03*
X712598Y459729D03*
X720198D03*
X733700Y469400D03*
X726100D03*
X712100Y467900D03*
X719700D03*
X712034Y475600D03*
X719634D03*
X712034Y483400D03*
X719634D03*
X702700D03*
G54D42*
X62500Y292200D03*
Y287200D03*
Y282200D03*
Y277200D03*
X42500D03*
Y282200D03*
Y287200D03*
Y292200D03*
X62404Y319922D03*
Y314922D03*
Y309922D03*
Y304922D03*
X42404D03*
Y309922D03*
Y314922D03*
Y319922D03*
G54D51*
X94488Y464075D03*
X102362D03*
X110236D03*
X118110D03*
X125984D03*
X133858D03*
X94488Y480807D03*
X102362D03*
X110236D03*
X118110D03*
X125984D03*
X133858D03*
X141732Y464075D03*
Y480807D03*
G54D16*
X52907Y175552D03*
X71800Y221000D03*
X31300Y211900D03*
X32649Y191548D03*
X46700Y190700D03*
X71800Y321700D03*
X70600Y338000D03*
X27900Y337800D03*
X48900Y337600D03*
X57300Y391050D03*
X57280Y399390D03*
X91695Y337793D03*
X177500Y114500D03*
X193413Y118544D03*
X201094Y209985D03*
X249045Y279732D03*
X207600Y287800D03*
X218200Y484000D03*
X275526Y278333D03*
X277100Y328400D03*
X350700Y347500D03*
X328908Y439668D03*
X535700Y418400D03*
X618200Y166500D03*
X597237Y284017D03*
X621700Y288745D03*
X593700Y334350D03*
X621700Y327654D03*
X593700Y337900D03*
X591870Y426720D03*
X586500Y490400D03*
X665483Y347018D03*
X668167Y396181D03*
X750308Y280164D03*
X728100Y463900D03*
X735520Y427980D03*
G54D25*
X43487Y166781D03*
X39612Y174281D03*
X47362D03*
X656500Y63250D03*
X660375Y70750D03*
X652625D03*
G54D52*
X149100Y136500D03*
X152700D03*
G54D61*
X223549Y81399D03*
X226109D03*
X228669D03*
Y87899D03*
X223549D03*
X243049Y81399D03*
X245609D03*
X248169D03*
Y87899D03*
X243049D03*
X292378Y304389D03*
X294938D03*
X297498D03*
Y310889D03*
X292378D03*
X279378Y304389D03*
X281938D03*
X284498D03*
Y310889D03*
X279378D03*
X327365Y422661D03*
X332485D03*
Y429161D03*
X329925D03*
X327365D03*
X670494Y425456D03*
X675614D03*
Y431956D03*
X673054D03*
X670494D03*
G54D70*
X289500Y136500D03*
Y147500D03*
Y167500D03*
Y156500D03*
Y239500D03*
Y209000D03*
Y198000D03*
Y178500D03*
Y189500D03*
Y220000D03*
Y231000D03*
Y250500D03*
X573500Y401500D03*
Y390500D03*
G54D43*
X75400Y318200D03*
X50300Y387500D03*
X77700Y291700D03*
X99450Y452650D03*
X225800Y95000D03*
X245300D03*
X242600Y279700D03*
X235400Y316900D03*
X253775Y316967D03*
X218000Y317000D03*
X273165Y317151D03*
X294900Y328300D03*
X360100Y334000D03*
X629800Y166500D03*
X632800Y299091D03*
Y288745D03*
Y337500D03*
Y327654D03*
X626370Y369320D03*
X627070Y389940D03*
X590150Y482900D03*
X599300Y434500D03*
X693535Y441196D03*
X717700Y489400D03*
G54D34*
X59800Y183100D03*
X82600Y222700D03*
X176500Y169800D03*
X178500Y193200D03*
X297000Y159200D03*
X296500Y200300D03*
Y242350D03*
X569070Y460430D03*
X581000Y392700D03*
X695700Y390250D03*
X647623Y378489D03*
X642907D03*
X715800Y381800D03*
X736400Y456600D03*
G54D53*
X185789Y175500D03*
Y180500D03*
X208011Y175500D03*
Y190500D03*
Y185500D03*
Y180500D03*
G54D80*
X564065Y229550D03*
X561865D03*
X564065Y227250D03*
X561865D03*
X562430Y235988D03*
X560230D03*
X562430Y238288D03*
X560230D03*
X561540Y245859D03*
X559340D03*
X561540Y243559D03*
X559340D03*
X563219Y253446D03*
X561019D03*
X563219Y251146D03*
X561019D03*
G54D26*
X66403Y140952D03*
X59997D03*
G54D35*
X61790Y199650D03*
X48010D03*
Y219750D03*
X61790D03*
G54D44*
X71165Y357207D03*
X73725D03*
X76285D03*
Y344407D03*
X73725D03*
X71165D03*
X28465Y357007D03*
X31025D03*
X33585D03*
X36145D03*
Y344207D03*
X33585D03*
X31025D03*
X28465D03*
X49465Y356807D03*
X52025D03*
X54585D03*
X57145D03*
Y344007D03*
X54585D03*
X52025D03*
X49465D03*
X78845Y357207D03*
Y344407D03*
X92260Y357000D03*
X94820D03*
X97380D03*
X99940D03*
Y344200D03*
X97380D03*
X94820D03*
X92260D03*
X234872Y298705D03*
X232312D03*
X229752D03*
X227192D03*
X253215Y298667D03*
X250655D03*
X248095D03*
X245535D03*
X216640Y298700D03*
X214080D03*
X211520D03*
X208960D03*
X227192Y311505D03*
X229752D03*
X232312D03*
X234872D03*
X245535Y311467D03*
X248095D03*
X250655D03*
X253215D03*
X208960Y311500D03*
X211520D03*
X214080D03*
X216640D03*
X272637Y298956D03*
X270077D03*
X267517D03*
X264957D03*
Y311756D03*
X267517D03*
X270077D03*
X272637D03*
G54D71*
X272368Y395524D03*
G54D17*
X26500Y160300D03*
X49700Y398200D03*
X242733Y70311D03*
X223995Y70291D03*
X226200Y408200D03*
X275500Y409300D03*
X344891Y209640D03*
X691400Y394700D03*
X652200Y370100D03*
X757488Y301161D03*
X713150Y453795D03*
X778440Y282210D03*
X786560Y328230D03*
G54D62*
X261102Y75310D03*
Y73735D03*
Y72160D03*
Y70585D03*
Y69010D03*
Y67435D03*
Y65865D03*
Y64290D03*
Y62715D03*
Y61140D03*
Y59565D03*
Y57990D03*
X283302D03*
Y59565D03*
Y61140D03*
Y62715D03*
Y64290D03*
Y65865D03*
Y67435D03*
Y69010D03*
Y70585D03*
Y72160D03*
Y73735D03*
Y75310D03*
X322650Y278826D03*
Y277251D03*
Y275676D03*
Y274101D03*
Y272526D03*
Y270951D03*
Y269381D03*
Y267806D03*
Y266231D03*
Y264656D03*
Y263081D03*
Y261506D03*
X344850D03*
Y263081D03*
Y264656D03*
Y266231D03*
Y267806D03*
Y269381D03*
Y270951D03*
Y272526D03*
Y274101D03*
Y275676D03*
Y277251D03*
Y278826D03*
G54D63*
X235500Y147500D03*
X260300D03*
X234750Y238600D03*
X259550D03*
X234700Y213500D03*
X259500D03*
X211600Y456500D03*
X236400D03*
X520600Y445500D03*
X545400D03*
X741293Y355942D03*
X716493D03*
X741293Y330892D03*
X716493D03*
G54D45*
X77257Y392835D03*
Y395395D03*
Y397955D03*
X70757D03*
Y392835D03*
X36850Y398560D03*
Y396000D03*
Y393440D03*
X43350D03*
Y398560D03*
G54D27*
X66403Y133450D03*
X59997D03*
G54D90*
X614043Y465943D03*
Y463974D03*
Y462006D03*
Y460037D03*
Y458069D03*
Y456100D03*
Y454131D03*
Y452163D03*
Y450194D03*
Y448226D03*
Y446257D03*
X594757D03*
Y448226D03*
Y450194D03*
Y452163D03*
Y454131D03*
Y456100D03*
Y458069D03*
Y460037D03*
Y462006D03*
Y463974D03*
Y465943D03*
G54D36*
X59821Y199950D03*
X57853D03*
X55884D03*
X53916D03*
X51947D03*
X49979D03*
Y219450D03*
X51947D03*
X53916D03*
X55884D03*
X57853D03*
X59821D03*
G54D54*
X196900Y183000D03*
G54D18*
X26500Y156700D03*
X49700Y394600D03*
X242733Y66711D03*
X223995Y66691D03*
X226200Y404600D03*
X275500Y405700D03*
X344891Y206040D03*
X691400Y391100D03*
X652200Y366500D03*
X757488Y297561D03*
X713150Y450195D03*
X778440Y278610D03*
X786560Y324630D03*
G54D81*
X535313Y298880D03*
X537513D03*
X535313Y296680D03*
X537513D03*
X535048Y306421D03*
X537248D03*
X535048Y304221D03*
X537248D03*
X535228Y311698D03*
X537428D03*
X535300Y319400D03*
X537500D03*
X535228Y313898D03*
X537428D03*
X535300Y317200D03*
X537500D03*
G54D72*
X269668Y395524D03*
G54D46*
X69300Y372000D03*
X26100Y371552D03*
X46900Y371433D03*
X89895Y371626D03*
X164810Y143631D03*
X189413Y114544D03*
X279000Y405700D03*
X348597Y217040D03*
X337900Y424200D03*
X598152Y362741D03*
X598023Y386411D03*
X690500Y382000D03*
X683781Y392333D03*
X701120Y433820D03*
X797155Y293467D03*
X805300Y267200D03*
G54D73*
X341757Y215563D03*
X335701D03*
X341757Y219461D03*
X335701D03*
G54D37*
X44850Y202810D03*
Y216590D03*
X64950D03*
Y202810D03*
G54D82*
X560513Y441531D03*
X582399D03*
G54D19*
X52607Y171752D03*
X56607D03*
X72800Y186600D03*
X25900Y207000D03*
X65500Y234500D03*
X45938Y235404D03*
X41938D03*
X64100Y187800D03*
X46500Y186900D03*
X50500D03*
X26600Y278900D03*
X27200Y305200D03*
X65500Y375500D03*
X22000Y375052D03*
X43000Y374933D03*
X73100Y375500D03*
X29900Y375052D03*
X50700Y374933D03*
X87300Y227100D03*
X89800Y186800D03*
X85795Y375126D03*
X93695D03*
X89600Y394600D03*
X195161Y131517D03*
X201139Y118095D03*
X156700Y136200D03*
X250791Y69127D03*
X238880Y70262D03*
X220227Y70215D03*
X238900Y287900D03*
X245800Y288000D03*
X219400Y287400D03*
X226600Y287900D03*
X260000D03*
X240200Y306800D03*
X258700Y304300D03*
X222000Y306700D03*
X255500Y419200D03*
X318050Y296600D03*
X267600Y287900D03*
X285400Y320800D03*
X283000Y409200D03*
X269500Y420200D03*
X343000Y305700D03*
X345121Y331450D03*
X370932Y323700D03*
X326083Y412566D03*
X412400Y343784D03*
X437500Y344200D03*
X427700Y344000D03*
X400300Y345100D03*
X469996Y354412D03*
X451400Y344200D03*
X460327Y344201D03*
X464327D03*
X482427Y358374D03*
X486627D03*
X497900Y345300D03*
X502700D03*
X507337Y345263D03*
X478298Y358254D03*
X480700Y344200D03*
X522000Y354850D03*
X512754Y345184D03*
X573570Y463680D03*
X590350Y330450D03*
X618900Y322800D03*
X631800Y322700D03*
X629370Y460030D03*
X586720Y476380D03*
X664301Y35265D03*
X664000Y57200D03*
X643492Y90136D03*
X639392D03*
X682700Y237200D03*
X695600D03*
X695100Y381700D03*
X675831Y396033D03*
X670610Y418830D03*
X675380Y457860D03*
X667900Y446600D03*
X755523Y93515D03*
X751023D03*
X699600Y237200D03*
X743600Y224400D03*
X739500D03*
X734286Y224423D03*
X726656Y231898D03*
X719300Y220900D03*
X759651Y266807D03*
X751470Y310720D03*
X700200Y381700D03*
X763840Y266710D03*
X782800Y328170D03*
G54D28*
X26634Y150171D03*
X35000Y165500D03*
X58962Y161005D03*
X64862Y152205D03*
X58470Y118520D03*
X22839Y163817D03*
X34380Y203183D03*
X74700Y226300D03*
X69000Y226200D03*
X23453Y180973D03*
X76425Y191400D03*
X41617Y183405D03*
X54370Y180718D03*
X68400Y193400D03*
X55800Y226100D03*
X35200Y207400D03*
X76100Y197000D03*
X38850Y222450D03*
X63206Y226229D03*
X40400Y192100D03*
X71850Y216100D03*
X76500Y202400D03*
X59800Y193700D03*
X29650Y235500D03*
X46200Y226200D03*
X51200Y226100D03*
X38814Y180206D03*
X33691Y179468D03*
X69399Y281699D03*
X69500Y276700D03*
X69400Y287100D03*
X35600Y292500D03*
Y287000D03*
Y280800D03*
X56500Y239800D03*
X41450Y256479D03*
X35500Y319100D03*
Y314000D03*
X35918Y307565D03*
X69304Y309100D03*
X69400Y303900D03*
X69200Y314100D03*
X57325Y337545D03*
X62325Y337845D03*
X36325Y337745D03*
X41325Y338045D03*
X43600Y362649D03*
X72446Y364233D03*
X29706Y364053D03*
X72356Y383400D03*
X50486Y364064D03*
X65300Y363049D03*
X22600Y362849D03*
X28200Y382900D03*
X30400Y397100D03*
X64700Y399000D03*
X42076Y383750D03*
X112997Y117234D03*
X112100Y124500D03*
X119700Y124600D03*
X93000Y147000D03*
X84800Y147100D03*
X100900Y147000D03*
X109100Y147100D03*
X116264Y136064D03*
X119700Y147200D03*
X133800Y165900D03*
X77600Y210700D03*
X79050Y217150D03*
X78805Y337855D03*
X84025Y338245D03*
X100270Y337248D03*
X105480Y338030D03*
X79292Y380900D03*
X93641Y364266D03*
X86395Y362842D03*
X99912Y412200D03*
X98614Y391150D03*
X84536Y390405D03*
Y395405D03*
X170050Y109625D03*
X165097Y139545D03*
X164810Y151500D03*
X190424Y122651D03*
X176500Y161200D03*
X184700Y159000D03*
X165319Y134201D03*
X162500Y128600D03*
X176083Y118985D03*
X190461Y128067D03*
X183498Y151582D03*
X183760Y118548D03*
X151697Y131670D03*
X164900Y123300D03*
X143655Y174344D03*
X181489Y208606D03*
X177550Y180450D03*
X153855Y184292D03*
X162523Y183631D03*
X171411Y184292D03*
X194000Y288000D03*
X198700Y289500D03*
X183901Y274213D03*
X259609Y52025D03*
X253613Y61140D03*
X231753Y60341D03*
X236750Y83000D03*
X223544Y74403D03*
X242733Y74428D03*
X250500Y95000D03*
X214350Y81543D03*
X258750Y85000D03*
X223650Y131900D03*
X255993Y130718D03*
X232300Y292200D03*
X251800Y292300D03*
X261600D03*
X246800Y292400D03*
X239700Y292600D03*
X227200Y292300D03*
X220900Y292500D03*
X240000Y298200D03*
X258800Y296500D03*
X221800Y298800D03*
X211300Y292302D03*
X216068Y260413D03*
X204368Y258164D03*
X228668Y262713D03*
X259690Y320875D03*
X245943Y322043D03*
X242091Y327293D03*
X227500Y318900D03*
X226500Y327500D03*
X214200Y324200D03*
X208960Y318800D03*
X221747Y384384D03*
X226200Y400600D03*
X230300Y407700D03*
X235300Y405400D03*
X248204Y372309D03*
X243664Y368975D03*
X243400Y378645D03*
X262672Y460813D03*
X283223Y29000D03*
X283173Y38000D03*
X287963Y33500D03*
X286848Y42500D03*
X296092Y93239D03*
X289398Y96815D03*
X322470Y111347D03*
X300168Y97933D03*
X306595Y98693D03*
X306196Y106297D03*
X311293Y109977D03*
X315932Y104519D03*
X294644Y60800D03*
X294822Y66022D03*
X279615Y88546D03*
X294914Y71626D03*
X271864Y82126D03*
X323484Y105921D03*
X289793Y85901D03*
X268962Y88452D03*
X291970Y76090D03*
X279804Y175047D03*
X292500Y125500D03*
X307369Y115952D03*
X302500Y115000D03*
X301400Y190000D03*
X281000Y218500D03*
X300943Y235180D03*
X273200Y219700D03*
X320628Y238548D03*
X325611Y296231D03*
X313650Y298850D03*
X274376Y250699D03*
X271800Y292600D03*
X266600Y292300D03*
X289817Y283261D03*
X297038Y285956D03*
X282362Y292400D03*
X280087Y283473D03*
X289056Y296534D03*
X316847Y243024D03*
X271468Y272013D03*
X267668Y267313D03*
X291268Y265113D03*
X285268Y269713D03*
X323950Y255200D03*
X265365Y320651D03*
X299791Y352123D03*
X285400Y326792D03*
X299100Y324500D03*
X294950Y317400D03*
X277250Y317700D03*
X279719Y383549D03*
X275782Y388274D03*
X280549Y391744D03*
X269500Y409600D03*
X275500Y413800D03*
X269954Y402990D03*
X283050Y413600D03*
X269977Y373425D03*
X266111Y379351D03*
X326632Y122343D03*
X327500Y134028D03*
X359000Y135000D03*
X377000Y289500D03*
X379257Y298785D03*
X377500Y283900D03*
Y277500D03*
X371437Y293000D03*
X361800Y245800D03*
X355700Y242500D03*
X350303Y238898D03*
X344600Y248800D03*
X374513Y265662D03*
X333054Y256852D03*
X356500Y266300D03*
X338054Y256852D03*
X334735Y303062D03*
X378500Y306500D03*
X350750Y343000D03*
X348900Y319600D03*
X350298Y333944D03*
X357895Y309272D03*
X351341Y313694D03*
X364596Y325590D03*
X366042Y318443D03*
X333794Y405044D03*
X326083Y416366D03*
X330531Y416439D03*
X332485Y435750D03*
X434083Y148279D03*
X444866Y152736D03*
X448416Y162119D03*
X430409Y335154D03*
X416841Y335528D03*
X395603Y345150D03*
X407304Y343726D03*
X430464Y351272D03*
X471096Y110797D03*
X479435Y105501D03*
X482779Y114109D03*
X470537Y105272D03*
X479830Y120100D03*
X477011Y126263D03*
X494472Y123575D03*
X490923Y130166D03*
X487008Y137123D03*
X464994Y146129D03*
X457326Y150586D03*
X472891Y154886D03*
X465088Y157094D03*
X456471Y159418D03*
X459221Y355189D03*
X510200Y359400D03*
X502450Y361450D03*
X494517Y335499D03*
X499517Y335504D03*
X509645Y335582D03*
X504581Y335524D03*
X491474Y342209D03*
X488444Y338409D03*
X486281Y346317D03*
X483500Y336000D03*
X472724Y335567D03*
X517097Y338315D03*
X518984Y419591D03*
X552200Y399200D03*
X542300Y399400D03*
X548400Y423600D03*
X566182Y423300D03*
X564415Y380334D03*
X566103Y386434D03*
X559514Y384907D03*
X569152Y378908D03*
X561746Y480600D03*
X551550Y480550D03*
X633000Y18000D03*
X632343Y55642D03*
X630888Y284129D03*
X625250Y284066D03*
X602273Y288661D03*
X614273D03*
X608273D03*
X629250Y332319D03*
X597250Y342400D03*
X606225Y356075D03*
X605900Y350800D03*
X610982Y348239D03*
X616800Y348100D03*
X608607Y326656D03*
X612907Y321774D03*
X624108Y322850D03*
X596631Y330137D03*
X608157Y310168D03*
X615900Y309900D03*
X612300Y378500D03*
Y373500D03*
X616600Y394600D03*
X592475Y382413D03*
X605070Y378970D03*
X592513Y376121D03*
X605600Y373500D03*
X622109Y385304D03*
Y364424D03*
X590400Y421200D03*
X625187Y378210D03*
X629602Y375862D03*
X599500Y480000D03*
X624898Y486518D03*
X613000Y484000D03*
X590640Y472600D03*
X600600Y430701D03*
X597140Y473590D03*
X582855Y476795D03*
X595500Y439400D03*
X627718Y473130D03*
X621500Y468000D03*
X633100Y449500D03*
X607500Y487500D03*
X581500Y489700D03*
X660500Y24600D03*
X657000Y46500D03*
X657440Y31815D03*
X660692Y42436D03*
X643103Y17648D03*
X638103Y16800D03*
X665012Y65659D03*
X645078Y61949D03*
X642000Y57500D03*
X636943Y57942D03*
X695151Y255091D03*
X689680Y261152D03*
X689764Y255264D03*
X683390Y302820D03*
X637500Y353500D03*
X652708Y378812D03*
X682000Y372160D03*
X655643Y389328D03*
X683563Y387733D03*
X695700Y385740D03*
X689800Y400850D03*
X663667Y395700D03*
X684100Y382050D03*
X678970Y400560D03*
X681800Y366200D03*
X663706Y423000D03*
X680560Y407500D03*
X661650Y390100D03*
X680000Y473500D03*
X677882Y449120D03*
X690000Y437000D03*
X695980Y432800D03*
X690690Y424820D03*
X742523Y100815D03*
X727727Y94148D03*
X719365Y96773D03*
X745700Y149600D03*
X747350Y165050D03*
X744552Y170076D03*
X744300Y160815D03*
X753050Y138650D03*
X749680Y169550D03*
X745351Y144396D03*
X752700Y143850D03*
X748000Y138330D03*
X712720Y229666D03*
X757337Y271913D03*
X760000Y290500D03*
X757483Y305724D03*
Y310924D03*
X716500Y376500D03*
X708337Y390944D03*
X716000Y393000D03*
X721100Y387500D03*
X735943Y475465D03*
X710268Y446055D03*
X700900Y441785D03*
X729837Y428237D03*
X736130Y451570D03*
X714400Y442500D03*
X743160Y428240D03*
X724340Y443410D03*
X784767Y84511D03*
X765615Y157200D03*
X762350Y186150D03*
X770351Y176500D03*
X783390Y286000D03*
X779890Y289000D03*
X767532Y289746D03*
X763840Y271430D03*
X776518Y246482D03*
X767663Y250993D03*
X763505Y316008D03*
X789597Y306335D03*
X789658Y301111D03*
X791520Y327000D03*
G54D91*
X696850Y111811D03*
X693700D03*
X690551D03*
X687401D03*
X684252D03*
X681102D03*
X677952D03*
X674803D03*
X671653D03*
X668504D03*
X665354D03*
X662204D03*
X659055D03*
X655905D03*
X652756D03*
X696850Y114960D03*
X693700D03*
X690551D03*
X687401D03*
X684252D03*
X681102D03*
X677952D03*
X674803D03*
X671653D03*
X668504D03*
X665354D03*
X662204D03*
X659055D03*
X655905D03*
X652756D03*
X696850Y118110D03*
X693700D03*
X690551D03*
X687401D03*
X684252D03*
X681102D03*
X677952D03*
X674803D03*
X671653D03*
X668504D03*
X665354D03*
X662204D03*
X659055D03*
X655905D03*
X652756D03*
X696850Y121260D03*
X693700D03*
X690551D03*
X687401D03*
X684252D03*
X681102D03*
X677952D03*
X674803D03*
X671653D03*
X668504D03*
X665354D03*
X662204D03*
X659055D03*
X655905D03*
X652756D03*
X649606D03*
X646456D03*
X643307D03*
X696850Y124409D03*
X693700D03*
X690551D03*
X687401D03*
X684252D03*
X681102D03*
X677952D03*
X674803D03*
X671653D03*
X668504D03*
X665354D03*
X662204D03*
X659055D03*
X655905D03*
X652756D03*
X649606D03*
X646456D03*
X643307D03*
X696850Y127559D03*
X693700D03*
X690551D03*
X687401D03*
X684252D03*
X681102D03*
X677952D03*
X674803D03*
X671653D03*
X668504D03*
X665354D03*
X662204D03*
X659055D03*
X655905D03*
X652756D03*
X649606D03*
X646456D03*
X643307D03*
X696850Y130708D03*
X693700D03*
X690551D03*
X687401D03*
X684252D03*
X681102D03*
X677952D03*
X674803D03*
X671653D03*
X668504D03*
X665354D03*
X662204D03*
X659055D03*
X655905D03*
X652756D03*
X649606D03*
X646456D03*
X643307D03*
X696850Y133858D03*
X693700D03*
X690551D03*
X687401D03*
X684252D03*
X681102D03*
X677952D03*
X674803D03*
X671653D03*
X668504D03*
X665354D03*
X662204D03*
X659055D03*
X655905D03*
X652756D03*
X649606D03*
X646456D03*
X643307D03*
X696850Y137008D03*
X693700D03*
X690551D03*
X687401D03*
X684252D03*
X681102D03*
X677952D03*
X674803D03*
X671653D03*
X668504D03*
X665354D03*
X662204D03*
X659055D03*
X655905D03*
X652756D03*
X649606D03*
X646456D03*
X643307D03*
X696850Y140157D03*
X693700D03*
X690551D03*
X687401D03*
X684252D03*
X681102D03*
X677952D03*
X674803D03*
X671653D03*
X668504D03*
X665354D03*
X662204D03*
X659055D03*
X655905D03*
X652756D03*
X649606D03*
X646456D03*
X643307D03*
X696850Y143307D03*
X693700D03*
X690551D03*
X687401D03*
X684252D03*
X681102D03*
X677952D03*
X674803D03*
X671653D03*
X668504D03*
X665354D03*
X662204D03*
X659055D03*
X655905D03*
X652756D03*
X649606D03*
X646456D03*
X643307D03*
X696850Y146456D03*
X693700D03*
X690551D03*
X687401D03*
X684252D03*
X681102D03*
X677952D03*
X674803D03*
X671653D03*
X668504D03*
X665354D03*
X662204D03*
X659055D03*
X655905D03*
X652756D03*
X649606D03*
X646456D03*
X643307D03*
X696850Y149606D03*
X693700D03*
X690551D03*
X687401D03*
X684252D03*
X681102D03*
X677952D03*
X674803D03*
X671653D03*
X668504D03*
X665354D03*
X662204D03*
X659055D03*
X655905D03*
X652756D03*
X649606D03*
X646456D03*
X643307D03*
X696850Y152756D03*
X693700D03*
X690551D03*
X687401D03*
X684252D03*
X681102D03*
X677952D03*
X674803D03*
X671653D03*
X668504D03*
X665354D03*
X662204D03*
X659055D03*
X655905D03*
X652756D03*
X649606D03*
X646456D03*
X643307D03*
X696850Y155905D03*
X693700D03*
X690551D03*
X687401D03*
X684252D03*
X681102D03*
X677952D03*
X674803D03*
X671653D03*
X668504D03*
X665354D03*
X662204D03*
X659055D03*
X655905D03*
X652756D03*
X649606D03*
X646456D03*
X643307D03*
X696850Y159055D03*
X693700D03*
X690551D03*
X687401D03*
X684252D03*
X681102D03*
X677952D03*
X674803D03*
X671653D03*
X668504D03*
X665354D03*
X662204D03*
X659055D03*
X655905D03*
X652756D03*
X649606D03*
X646456D03*
X643307D03*
X696850Y162204D03*
X693700D03*
X690551D03*
X687401D03*
X684252D03*
X681102D03*
X677952D03*
X674803D03*
X671653D03*
X668504D03*
X665354D03*
X662204D03*
X659055D03*
X655905D03*
X652756D03*
X649606D03*
X646456D03*
X643307D03*
X696850Y165354D03*
X693700D03*
X690551D03*
X687401D03*
X684252D03*
X681102D03*
X677952D03*
X674803D03*
X671653D03*
X668504D03*
X665354D03*
X662204D03*
X659055D03*
X655905D03*
X652756D03*
X649606D03*
X646456D03*
X643307D03*
X696850Y168504D03*
X693700D03*
X690551D03*
X687401D03*
X684252D03*
X681102D03*
X677952D03*
X674803D03*
X671653D03*
X668504D03*
X665354D03*
X662204D03*
X659055D03*
X655905D03*
X652756D03*
X649606D03*
X646456D03*
X643307D03*
X696850Y171653D03*
X693700D03*
X690551D03*
X687401D03*
X684252D03*
X681102D03*
X677952D03*
X674803D03*
X671653D03*
X668504D03*
X665354D03*
X662204D03*
X659055D03*
X655905D03*
X652756D03*
X649606D03*
X646456D03*
X643307D03*
X696850Y174803D03*
X693700D03*
X690551D03*
X687401D03*
X684252D03*
X681102D03*
X677952D03*
X674803D03*
X671653D03*
X668504D03*
X665354D03*
X662204D03*
X659055D03*
X655905D03*
X652756D03*
X649606D03*
X646456D03*
X643307D03*
X696850Y177952D03*
X693700D03*
X690551D03*
X687401D03*
X684252D03*
X681102D03*
X677952D03*
X674803D03*
X671653D03*
X668504D03*
X665354D03*
X662204D03*
X659055D03*
X655905D03*
X652756D03*
X649606D03*
X646456D03*
X643307D03*
X696850Y181102D03*
X693700D03*
X690551D03*
X687401D03*
X684252D03*
X681102D03*
X677952D03*
X674803D03*
X671653D03*
X668504D03*
X665354D03*
X662204D03*
X659055D03*
X655905D03*
X652756D03*
X649606D03*
X646456D03*
X643307D03*
X696850Y184252D03*
X693700D03*
X690551D03*
X687401D03*
X684252D03*
X681102D03*
X677952D03*
X674803D03*
X671653D03*
X668504D03*
X665354D03*
X662204D03*
X659055D03*
X655905D03*
X652756D03*
X649606D03*
X646456D03*
X643307D03*
X696850Y187401D03*
X693700D03*
X690551D03*
X687401D03*
X684252D03*
X681102D03*
X677952D03*
X674803D03*
X671653D03*
X668504D03*
X665354D03*
X662204D03*
X659055D03*
X655905D03*
X652756D03*
X649606D03*
X646456D03*
X643307D03*
X696850Y190551D03*
X693700D03*
X690551D03*
X687401D03*
X684252D03*
X681102D03*
X677952D03*
X674803D03*
X671653D03*
X668504D03*
X665354D03*
X662204D03*
X659055D03*
X655905D03*
X652756D03*
X649606D03*
X646456D03*
X643307D03*
X696850Y193700D03*
X693700D03*
X690551D03*
X687401D03*
X684252D03*
X681102D03*
X677952D03*
X674803D03*
X671653D03*
X668504D03*
X665354D03*
X662204D03*
X659055D03*
X655905D03*
X652756D03*
X649606D03*
X646456D03*
X643307D03*
X696850Y196850D03*
X693700D03*
X690551D03*
X687401D03*
X684252D03*
X681102D03*
X677952D03*
X674803D03*
X671653D03*
X668504D03*
X665354D03*
X662204D03*
X659055D03*
X655905D03*
X652756D03*
X696850Y200000D03*
X693700D03*
X690551D03*
X687401D03*
X684252D03*
X681102D03*
X677952D03*
X674803D03*
X671653D03*
X668504D03*
X665354D03*
X662204D03*
X659055D03*
X655905D03*
X652756D03*
X696850Y203149D03*
X693700D03*
X690551D03*
X687401D03*
X684252D03*
X681102D03*
X677952D03*
X674803D03*
X671653D03*
X668504D03*
X665354D03*
X662204D03*
X659055D03*
X655905D03*
X652756D03*
X725196Y111811D03*
X722047D03*
X718897D03*
X715748D03*
X712598D03*
X709448D03*
X706299D03*
X703149D03*
X700000D03*
X725196Y114960D03*
X722047D03*
X718897D03*
X715748D03*
X712598D03*
X709448D03*
X706299D03*
X703149D03*
X700000D03*
X725196Y118110D03*
X722047D03*
X718897D03*
X715748D03*
X712598D03*
X709448D03*
X706299D03*
X703149D03*
X700000D03*
X734645Y121260D03*
X731496D03*
X728346D03*
X725196D03*
X722047D03*
X718897D03*
X715748D03*
X712598D03*
X709448D03*
X706299D03*
X703149D03*
X700000D03*
X734645Y124409D03*
X731496D03*
X728346D03*
X725196D03*
X722047D03*
X718897D03*
X715748D03*
X712598D03*
X709448D03*
X706299D03*
X703149D03*
X700000D03*
X734645Y127559D03*
X731496D03*
X728346D03*
X725196D03*
X722047D03*
X718897D03*
X715748D03*
X712598D03*
X709448D03*
X706299D03*
X703149D03*
X700000D03*
X734645Y130708D03*
X731496D03*
X728346D03*
X725196D03*
X722047D03*
X718897D03*
X715748D03*
X712598D03*
X709448D03*
X706299D03*
X703149D03*
X700000D03*
X734645Y133858D03*
X731496D03*
X728346D03*
X725196D03*
X722047D03*
X718897D03*
X715748D03*
X712598D03*
X709448D03*
X706299D03*
X703149D03*
X700000D03*
X734645Y137008D03*
X731496D03*
X728346D03*
X725196D03*
X722047D03*
X718897D03*
X715748D03*
X712598D03*
X709448D03*
X706299D03*
X703149D03*
X700000D03*
X734645Y140157D03*
X731496D03*
X728346D03*
X725196D03*
X722047D03*
X718897D03*
X715748D03*
X712598D03*
X709448D03*
X706299D03*
X703149D03*
X700000D03*
X734645Y143307D03*
X731496D03*
X728346D03*
X725196D03*
X722047D03*
X718897D03*
X715748D03*
X712598D03*
X709448D03*
X706299D03*
X703149D03*
X700000D03*
X734645Y146456D03*
X731496D03*
X728346D03*
X725196D03*
X722047D03*
X718897D03*
X715748D03*
X712598D03*
X709448D03*
X706299D03*
X703149D03*
X700000D03*
X734645Y149606D03*
X731496D03*
X728346D03*
X725196D03*
X722047D03*
X718897D03*
X715748D03*
X712598D03*
X709448D03*
X706299D03*
X703149D03*
X700000D03*
X734645Y152756D03*
X731496D03*
X728346D03*
X725196D03*
X722047D03*
X718897D03*
X715748D03*
X712598D03*
X709448D03*
X706299D03*
X703149D03*
X700000D03*
X734645Y155905D03*
X731496D03*
X728346D03*
X725196D03*
X722047D03*
X718897D03*
X715748D03*
X712598D03*
X709448D03*
X706299D03*
X703149D03*
X700000D03*
X734645Y159055D03*
X731496D03*
X728346D03*
X725196D03*
X722047D03*
X718897D03*
X715748D03*
X712598D03*
X709448D03*
X706299D03*
X703149D03*
X700000D03*
X734645Y162204D03*
X731496D03*
X728346D03*
X725196D03*
X722047D03*
X718897D03*
X715748D03*
X712598D03*
X709448D03*
X706299D03*
X703149D03*
X700000D03*
X734645Y165354D03*
X731496D03*
X728346D03*
X725196D03*
X722047D03*
X718897D03*
X715748D03*
X712598D03*
X709448D03*
X706299D03*
X703149D03*
X700000D03*
X734645Y168504D03*
X731496D03*
X728346D03*
X725196D03*
X722047D03*
X718897D03*
X715748D03*
X712598D03*
X709448D03*
X706299D03*
X703149D03*
X700000D03*
X734645Y171653D03*
X731496D03*
X728346D03*
X725196D03*
X722047D03*
X718897D03*
X715748D03*
X712598D03*
X709448D03*
X706299D03*
X703149D03*
X700000D03*
X734645Y174803D03*
X731496D03*
X728346D03*
X725196D03*
X722047D03*
X718897D03*
X715748D03*
X712598D03*
X709448D03*
X706299D03*
X703149D03*
X700000D03*
X734645Y177952D03*
X731496D03*
X728346D03*
X725196D03*
X722047D03*
X718897D03*
X715748D03*
X712598D03*
X709448D03*
X706299D03*
X703149D03*
X700000D03*
X734645Y181102D03*
X731496D03*
X728346D03*
X725196D03*
X722047D03*
X718897D03*
X715748D03*
X712598D03*
X709448D03*
X706299D03*
X703149D03*
X700000D03*
X734645Y184252D03*
X731496D03*
X728346D03*
X725196D03*
X722047D03*
X718897D03*
X715748D03*
X712598D03*
X709448D03*
X706299D03*
X703149D03*
X700000D03*
X734645Y187401D03*
X731496D03*
X728346D03*
X725196D03*
X722047D03*
X718897D03*
X715748D03*
X712598D03*
X709448D03*
X706299D03*
X703149D03*
X700000D03*
X734645Y190551D03*
X731496D03*
X728346D03*
X725196D03*
X722047D03*
X718897D03*
X715748D03*
X712598D03*
X709448D03*
X706299D03*
X703149D03*
X700000D03*
X734645Y193700D03*
X731496D03*
X728346D03*
X725196D03*
X722047D03*
X718897D03*
X715748D03*
X712598D03*
X709448D03*
X706299D03*
X703149D03*
X700000D03*
X725196Y196850D03*
X722047D03*
X718897D03*
X715748D03*
X712598D03*
X709448D03*
X706299D03*
X703149D03*
X700000D03*
X725196Y200000D03*
X722047D03*
X718897D03*
X715748D03*
X712598D03*
X709448D03*
X706299D03*
X703149D03*
X700000D03*
X725196Y203149D03*
X722047D03*
X718897D03*
X715748D03*
X712598D03*
X709448D03*
X706299D03*
X703149D03*
X700000D03*
G54D64*
X254124Y180500D03*
X221876D03*
G54D55*
X193264Y138748D03*
X605570Y475580D03*
G54D65*
X229700Y384200D03*
X254920Y376270D03*
G54D29*
X56541Y231086D03*
X75500Y231100D03*
X33700Y223500D03*
X76800Y183200D03*
X29900Y203600D03*
X70500Y231100D03*
X52400D03*
X32405Y184317D03*
X36405D03*
X30700Y275500D03*
X31400Y301800D03*
X25700Y388500D03*
X77200Y367100D03*
X38200Y366900D03*
X34100D03*
X60400Y366700D03*
X54800D03*
X25700Y396000D03*
X37500Y384000D03*
X85700Y183400D03*
X91300Y223700D03*
X93700Y391200D03*
X81300Y367100D03*
X98295Y366893D03*
X102395D03*
X246530Y66836D03*
X252000Y284500D03*
X230700D03*
X256000D03*
X234800Y284400D03*
X215300Y284000D03*
X271600Y284500D03*
X275600D03*
X294708Y292126D03*
X287214Y288217D03*
X323900Y247800D03*
X265250Y370750D03*
X279000Y398300D03*
X348597Y209640D03*
X365387Y258009D03*
X372119Y257880D03*
X384000Y341050D03*
X330531Y409161D03*
X416841Y340384D03*
X447300Y340800D03*
X472296D03*
X506200Y352300D03*
X499700D03*
X493200D03*
X476500Y340800D03*
X532894Y347615D03*
X528894D03*
X535336Y331822D03*
X541714Y331803D03*
X547315Y331788D03*
X551394D03*
X518000Y351450D03*
X514000Y351600D03*
X613211Y280205D03*
X608711D03*
X617000Y472800D03*
X621500D03*
X667353Y226932D03*
X641579Y227190D03*
X658610Y226975D03*
X663110D03*
X654464Y227115D03*
X650287Y227074D03*
X645968Y227097D03*
X691100Y233800D03*
X686900D03*
X678500D03*
X654770Y394660D03*
X658840D03*
X687581Y392433D03*
X686390Y424870D03*
X695380Y424850D03*
X731900Y88600D03*
X730712Y228507D03*
X738786Y228523D03*
X725750Y217572D03*
X712720Y234422D03*
X746970Y307320D03*
X700200Y391300D03*
X710200Y434530D03*
X717150Y450295D03*
X706120Y434530D03*
X743480Y432190D03*
X801934Y287746D03*
G54D47*
X69300Y375600D03*
X26100Y375152D03*
X46900Y375033D03*
X89895Y375226D03*
X164810Y147231D03*
X189413Y118144D03*
X279000Y409300D03*
X348597Y220640D03*
X337900Y427800D03*
X598152Y366341D03*
X598023Y390011D03*
X690500Y385600D03*
X683781Y395933D03*
X701120Y437420D03*
X797155Y297067D03*
X805300Y270800D03*
G54D74*
X340250Y292980D03*
X332750Y296855D03*
Y289105D03*
G54D38*
X45150Y204779D03*
Y206747D03*
Y208716D03*
Y210684D03*
Y212653D03*
Y214621D03*
X64650D03*
Y212653D03*
Y210684D03*
Y208716D03*
Y206747D03*
Y204779D03*
G54D83*
X562460Y462070D03*
Y471070D03*
G54D56*
X193264Y136048D03*
X605570Y472880D03*
G54D92*
X649606Y111811D03*
X646456D03*
X649606Y114960D03*
X646456D03*
X643307D03*
X649606Y118110D03*
X646456D03*
X643307D03*
X649606Y196850D03*
X646456D03*
X643307D03*
X649606Y200000D03*
X646456D03*
X643307D03*
X649606Y203149D03*
X646456D03*
X731496Y111811D03*
X728346D03*
X734645Y114960D03*
X731496D03*
X728346D03*
X734645Y118110D03*
X731496D03*
X728346D03*
X734645Y196850D03*
X731496D03*
X728346D03*
X734645Y200000D03*
X731496D03*
X728346D03*
X731496Y203149D03*
X728346D03*
G54D39*
X54900Y209700D03*
G54D93*
X684800Y313200D03*
X695800D03*
X720383Y412014D03*
X709383D03*
X720383Y403014D03*
X709383D03*
G54D57*
X171694Y134453D03*
Y132484D03*
Y130516D03*
Y128547D03*
X183906D03*
Y130516D03*
Y132484D03*
Y134453D03*
G54D48*
X88600Y199400D03*
Y209400D03*
Y204400D03*
X176100Y104500D03*
X194457Y153196D03*
X261800Y431000D03*
X280800Y141000D03*
X280300Y163000D03*
X280800Y204500D03*
X280300Y183000D03*
X280800Y224500D03*
X280300Y246000D03*
X324259Y301695D03*
X576100Y489700D03*
X694900Y306300D03*
X649260Y390820D03*
X690300Y377500D03*
G54D75*
X353556Y257143D03*
X353500Y262500D03*
X432200Y341500D03*
X421375Y346552D03*
X421357Y341201D03*
X465300Y351481D03*
X455900Y341100D03*
X493200Y347700D03*
X485500Y432820D03*
X490800D03*
X485500Y427520D03*
X490800D03*
Y443420D03*
X485500D03*
Y438120D03*
X490800D03*
X518020Y343632D03*
X523602Y345779D03*
X528902Y341725D03*
X678500Y227500D03*
X695600D03*
X686900D03*
X682700Y223300D03*
X691721D03*
X646318Y217778D03*
X671508Y220824D03*
X650684Y221630D03*
X654464Y217358D03*
X661452Y217241D03*
X664452Y222315D03*
X657920Y221560D03*
X641579Y221770D03*
X667166Y217194D03*
X675264Y216982D03*
X748500Y109750D03*
X754000Y109600D03*
X726039Y84955D03*
X759023Y97440D03*
X737100Y95600D03*
X760100Y130900D03*
X749200Y126250D03*
X755300Y131150D03*
X754000Y126250D03*
X760450Y119550D03*
X750400Y131050D03*
X701500Y219000D03*
X707000Y217500D03*
X748644Y191051D03*
X701500Y225500D03*
X760500Y126000D03*
X764900Y130800D03*
X765500Y119500D03*
X763500Y115000D03*
X765800Y125800D03*
X773000Y315800D03*
G54D84*
X634216Y47468D03*
Y25268D03*
X651536Y47468D03*
X649961D03*
X648386D03*
X646811D03*
X645236D03*
X643661D03*
X642091D03*
X640516D03*
X638941D03*
X637366D03*
X635791D03*
Y25268D03*
X637366D03*
X638941D03*
X640516D03*
X642091D03*
X643661D03*
X645236D03*
X646811D03*
X648386D03*
X649961D03*
X651536D03*
G54D66*
X235300Y384200D03*
X260520Y376270D03*
G54D85*
X623566Y173443D03*
X627464D03*
X623566Y179499D03*
X627464D03*
G54D58*
X180753Y137606D03*
X178784D03*
X176816D03*
X174847D03*
Y125394D03*
X176816D03*
X178784D03*
X180753D03*
G54D49*
X83000Y199400D03*
Y209400D03*
Y204400D03*
X170500Y104500D03*
X188857Y153196D03*
X256200Y431000D03*
X275200Y141000D03*
X274700Y163000D03*
X275200Y204500D03*
X274700Y183000D03*
X275200Y224500D03*
X274700Y246000D03*
X318659Y301695D03*
X570500Y489700D03*
X689300Y306300D03*
X643660Y390820D03*
X684700Y377500D03*
G54D67*
X251870Y395670D03*
G54D94*
X702000Y347771D03*
X678452D03*
G54D76*
X446850Y202756D03*
X442913D03*
X438976D03*
X435039D03*
X431102D03*
X427165D03*
X423228D03*
X419291D03*
X415354D03*
X411417D03*
X407480D03*
X403543D03*
X446850Y206693D03*
X442913D03*
X438976D03*
X435039D03*
X431102D03*
X427165D03*
X423228D03*
X419291D03*
X415354D03*
X411417D03*
X407480D03*
X403543D03*
X446850Y210630D03*
X442913D03*
X438976D03*
X435039D03*
X431102D03*
X427165D03*
X423228D03*
X419291D03*
X415354D03*
X411417D03*
X407480D03*
X403543D03*
X446850Y214567D03*
X442913D03*
X438976D03*
X435039D03*
X431102D03*
X427165D03*
X423228D03*
X419291D03*
X415354D03*
X411417D03*
X407480D03*
X403543D03*
X399606D03*
X395669D03*
X391732D03*
X446850Y218504D03*
X442913D03*
X438976D03*
X435039D03*
X431102D03*
X427165D03*
X423228D03*
X419291D03*
X415354D03*
X411417D03*
X407480D03*
X403543D03*
X399606D03*
X395669D03*
X391732D03*
X446850Y222441D03*
X442913D03*
X438976D03*
X435039D03*
X431102D03*
X427165D03*
X423228D03*
X419291D03*
X415354D03*
X411417D03*
X407480D03*
X403543D03*
X399606D03*
X395669D03*
X391732D03*
X446850Y226378D03*
X442913D03*
X438976D03*
X435039D03*
X431102D03*
X427165D03*
X423228D03*
X419291D03*
X415354D03*
X411417D03*
X407480D03*
X403543D03*
X399606D03*
X395669D03*
X391732D03*
X446850Y230315D03*
X442913D03*
X438976D03*
X435039D03*
X431102D03*
X427165D03*
X423228D03*
X419291D03*
X415354D03*
X411417D03*
X407480D03*
X403543D03*
X399606D03*
X395669D03*
X391732D03*
X446850Y234252D03*
X442913D03*
X438976D03*
X435039D03*
X431102D03*
X427165D03*
X423228D03*
X419291D03*
X415354D03*
X411417D03*
X407480D03*
X403543D03*
X399606D03*
X395669D03*
X391732D03*
X446850Y238189D03*
X442913D03*
X438976D03*
X435039D03*
X431102D03*
X427165D03*
X423228D03*
X419291D03*
X415354D03*
X411417D03*
X407480D03*
X403543D03*
X399606D03*
X395669D03*
X391732D03*
X446850Y242126D03*
X442913D03*
X438976D03*
X435039D03*
X431102D03*
X427165D03*
X423228D03*
X419291D03*
X415354D03*
X411417D03*
X407480D03*
X403543D03*
X399606D03*
X395669D03*
X391732D03*
X446850Y246063D03*
X442913D03*
X438976D03*
X435039D03*
X431102D03*
X427165D03*
X423228D03*
X419291D03*
X415354D03*
X411417D03*
X407480D03*
X403543D03*
X399606D03*
X395669D03*
X391732D03*
X446850Y250000D03*
X442913D03*
X438976D03*
X435039D03*
X431102D03*
X427165D03*
X423228D03*
X419291D03*
X415354D03*
X411417D03*
X407480D03*
X403543D03*
X399606D03*
X395669D03*
X391732D03*
X446850Y253937D03*
X442913D03*
X438976D03*
X435039D03*
X431102D03*
X427165D03*
X423228D03*
X419291D03*
X415354D03*
X411417D03*
X407480D03*
X403543D03*
X399606D03*
X395669D03*
X391732D03*
X446850Y257874D03*
X442913D03*
X438976D03*
X435039D03*
X431102D03*
X427165D03*
X423228D03*
X419291D03*
X415354D03*
X411417D03*
X407480D03*
X403543D03*
X399606D03*
X395669D03*
X391732D03*
X446850Y261811D03*
X442913D03*
X438976D03*
X435039D03*
X431102D03*
X427165D03*
X423228D03*
X419291D03*
X415354D03*
X411417D03*
X407480D03*
X403543D03*
X399606D03*
X395669D03*
X391732D03*
X446850Y265749D03*
X442913D03*
X438976D03*
X435039D03*
X431102D03*
X427165D03*
X423228D03*
X419291D03*
X415354D03*
X411417D03*
X407480D03*
X403543D03*
X399606D03*
X395669D03*
X391732D03*
X446850Y269686D03*
X442913D03*
X438976D03*
X435039D03*
X431102D03*
X427165D03*
X423228D03*
X419291D03*
X415354D03*
X411417D03*
X407480D03*
X403543D03*
X399606D03*
X395669D03*
X391732D03*
X446850Y273623D03*
X442913D03*
X438976D03*
X435039D03*
X431102D03*
X427165D03*
X423228D03*
X419291D03*
X415354D03*
X411417D03*
X407480D03*
X403543D03*
X399606D03*
X395669D03*
X391732D03*
X446850Y277560D03*
X442913D03*
X438976D03*
X435039D03*
X431102D03*
X427165D03*
X423228D03*
X419291D03*
X415354D03*
X411417D03*
X407480D03*
X403543D03*
X399606D03*
X395669D03*
X391732D03*
X446850Y281497D03*
X442913D03*
X438976D03*
X435039D03*
X431102D03*
X427165D03*
X423228D03*
X419291D03*
X415354D03*
X411417D03*
X407480D03*
X403543D03*
X399606D03*
X395669D03*
X391732D03*
X446850Y285434D03*
X442913D03*
X438976D03*
X435039D03*
X431102D03*
X427165D03*
X423228D03*
X419291D03*
X415354D03*
X411417D03*
X407480D03*
X403543D03*
X399606D03*
X395669D03*
X391732D03*
X446850Y289371D03*
X442913D03*
X438976D03*
X435039D03*
X431102D03*
X427165D03*
X423228D03*
X419291D03*
X415354D03*
X411417D03*
X407480D03*
X403543D03*
X399606D03*
X395669D03*
X391732D03*
X446850Y293308D03*
X442913D03*
X438976D03*
X435039D03*
X431102D03*
X427165D03*
X423228D03*
X419291D03*
X415354D03*
X411417D03*
X407480D03*
X403543D03*
X399606D03*
X395669D03*
X391732D03*
X446850Y297245D03*
X442913D03*
X438976D03*
X435039D03*
X431102D03*
X427165D03*
X423228D03*
X419291D03*
X415354D03*
X411417D03*
X407480D03*
X403543D03*
X399606D03*
X395669D03*
X391732D03*
X446850Y301182D03*
X442913D03*
X438976D03*
X435039D03*
X431102D03*
X427165D03*
X423228D03*
X419291D03*
X415354D03*
X411417D03*
X407480D03*
X403543D03*
X399606D03*
X395669D03*
X391732D03*
X446850Y305119D03*
X442913D03*
X438976D03*
X435039D03*
X431102D03*
X427165D03*
X423228D03*
X419291D03*
X415354D03*
X411417D03*
X407480D03*
X403543D03*
X399606D03*
X395669D03*
X391732D03*
X446850Y309056D03*
X442913D03*
X438976D03*
X435039D03*
X431102D03*
X427165D03*
X423228D03*
X419291D03*
X415354D03*
X411417D03*
X407480D03*
X403543D03*
X399606D03*
X395669D03*
X391732D03*
X446850Y312993D03*
X442913D03*
X438976D03*
X435039D03*
X431102D03*
X427165D03*
X423228D03*
X419291D03*
X415354D03*
X411417D03*
X407480D03*
X403543D03*
X399606D03*
X395669D03*
X391732D03*
X446850Y316930D03*
X442913D03*
X438976D03*
X435039D03*
X431102D03*
X427165D03*
X423228D03*
X419291D03*
X415354D03*
X411417D03*
X407480D03*
X403543D03*
X446850Y320867D03*
X442913D03*
X438976D03*
X435039D03*
X431102D03*
X427165D03*
X423228D03*
X419291D03*
X415354D03*
X411417D03*
X407480D03*
X403543D03*
X446850Y324804D03*
X442913D03*
X438976D03*
X435039D03*
X431102D03*
X427165D03*
X423228D03*
X419291D03*
X415354D03*
X411417D03*
X407480D03*
X403543D03*
X501969Y202756D03*
X498032D03*
X494095D03*
X490158D03*
X486221D03*
X482284D03*
X478347D03*
X474410D03*
X470473D03*
X466536D03*
X462599D03*
X458662D03*
X454725D03*
X450787D03*
X501969Y206693D03*
X498032D03*
X494095D03*
X490158D03*
X486221D03*
X482284D03*
X478347D03*
X474410D03*
X470473D03*
X466536D03*
X462599D03*
X458662D03*
X454725D03*
X450787D03*
X501969Y210630D03*
X498032D03*
X494095D03*
X490158D03*
X486221D03*
X482284D03*
X478347D03*
X474410D03*
X470473D03*
X466536D03*
X462599D03*
X458662D03*
X454725D03*
X450787D03*
X509843Y214567D03*
X505906D03*
X501969D03*
X498032D03*
X494095D03*
X490158D03*
X486221D03*
X482284D03*
X478347D03*
X474410D03*
X470473D03*
X466536D03*
X462599D03*
X458662D03*
X454725D03*
X450787D03*
X509843Y218504D03*
X505906D03*
X501969D03*
X498032D03*
X494095D03*
X490158D03*
X486221D03*
X482284D03*
X478347D03*
X474410D03*
X470473D03*
X466536D03*
X462599D03*
X458662D03*
X454725D03*
X450787D03*
X509843Y222441D03*
X505906D03*
X501969D03*
X498032D03*
X494095D03*
X490158D03*
X486221D03*
X482284D03*
X478347D03*
X474410D03*
X470473D03*
X466536D03*
X462599D03*
X458662D03*
X454725D03*
X450787D03*
X509843Y226378D03*
X505906D03*
X501969D03*
X498032D03*
X494095D03*
X490158D03*
X486221D03*
X482284D03*
X478347D03*
X474410D03*
X470473D03*
X466536D03*
X462599D03*
X458662D03*
X454725D03*
X450787D03*
X509843Y230315D03*
X505906D03*
X501969D03*
X498032D03*
X494095D03*
X490158D03*
X486221D03*
X482284D03*
X478347D03*
X474410D03*
X470473D03*
X466536D03*
X462599D03*
X458662D03*
X454725D03*
X450787D03*
X509843Y234252D03*
X505906D03*
X501969D03*
X498032D03*
X494095D03*
X490158D03*
X486221D03*
X482284D03*
X478347D03*
X474410D03*
X470473D03*
X466536D03*
X462599D03*
X458662D03*
X454725D03*
X450787D03*
X509843Y238189D03*
X505906D03*
X501969D03*
X498032D03*
X494095D03*
X490158D03*
X486221D03*
X482284D03*
X478347D03*
X474410D03*
X470473D03*
X466536D03*
X462599D03*
X458662D03*
X454725D03*
X450787D03*
X509843Y242126D03*
X505906D03*
X501969D03*
X498032D03*
X494095D03*
X490158D03*
X486221D03*
X482284D03*
X478347D03*
X474410D03*
X470473D03*
X466536D03*
X462599D03*
X458662D03*
X454725D03*
X450787D03*
X509843Y246063D03*
X505906D03*
X501969D03*
X498032D03*
X494095D03*
X490158D03*
X486221D03*
X482284D03*
X478347D03*
X474410D03*
X470473D03*
X466536D03*
X462599D03*
X458662D03*
X454725D03*
X450787D03*
X509843Y250000D03*
X505906D03*
X501969D03*
X498032D03*
X494095D03*
X490158D03*
X486221D03*
X482284D03*
X478347D03*
X474410D03*
X470473D03*
X466536D03*
X462599D03*
X458662D03*
X454725D03*
X450787D03*
X509843Y253937D03*
X505906D03*
X501969D03*
X498032D03*
X494095D03*
X490158D03*
X486221D03*
X482284D03*
X478347D03*
X474410D03*
X470473D03*
X466536D03*
X462599D03*
X458662D03*
X454725D03*
X450787D03*
X509843Y257874D03*
X505906D03*
X501969D03*
X498032D03*
X494095D03*
X490158D03*
X486221D03*
X482284D03*
X478347D03*
X474410D03*
X470473D03*
X466536D03*
X462599D03*
X458662D03*
X454725D03*
X450787D03*
X509843Y261811D03*
X505906D03*
X501969D03*
X498032D03*
X494095D03*
X490158D03*
X486221D03*
X482284D03*
X478347D03*
X474410D03*
X470473D03*
X466536D03*
X462599D03*
X458662D03*
X454725D03*
X450787D03*
X509843Y265749D03*
X505906D03*
X501969D03*
X498032D03*
X494095D03*
X490158D03*
X486221D03*
X482284D03*
X478347D03*
X474410D03*
X470473D03*
X466536D03*
X462599D03*
X458662D03*
X454725D03*
X450787D03*
X509843Y269686D03*
X505906D03*
X501969D03*
X498032D03*
X494095D03*
X490158D03*
X486221D03*
X482284D03*
X478347D03*
X474410D03*
X470473D03*
X466536D03*
X462599D03*
X458662D03*
X454725D03*
X450787D03*
X509843Y273623D03*
X505906D03*
X501969D03*
X498032D03*
X494095D03*
X490158D03*
X486221D03*
X482284D03*
X478347D03*
X474410D03*
X470473D03*
X466536D03*
X462599D03*
X458662D03*
X454725D03*
X450787D03*
X509843Y277560D03*
X505906D03*
X501969D03*
X498032D03*
X494095D03*
X490158D03*
X486221D03*
X482284D03*
X478347D03*
X474410D03*
X470473D03*
X466536D03*
X462599D03*
X458662D03*
X454725D03*
X450787D03*
X509843Y281497D03*
X505906D03*
X501969D03*
X498032D03*
X494095D03*
X490158D03*
X486221D03*
X482284D03*
X478347D03*
X474410D03*
X470473D03*
X466536D03*
X462599D03*
X458662D03*
X454725D03*
X450787D03*
X509843Y285434D03*
X505906D03*
X501969D03*
X498032D03*
X494095D03*
X490158D03*
X486221D03*
X482284D03*
X478347D03*
X474410D03*
X470473D03*
X466536D03*
X462599D03*
X458662D03*
X454725D03*
X450787D03*
X509843Y289371D03*
X505906D03*
X501969D03*
X498032D03*
X494095D03*
X490158D03*
X486221D03*
X482284D03*
X478347D03*
X474410D03*
X470473D03*
X466536D03*
X462599D03*
X458662D03*
X454725D03*
X450787D03*
X509843Y293308D03*
X505906D03*
X501969D03*
X498032D03*
X494095D03*
X490158D03*
X486221D03*
X482284D03*
X478347D03*
X474410D03*
X470473D03*
X466536D03*
X462599D03*
X458662D03*
X454725D03*
X450787D03*
X509843Y297245D03*
X505906D03*
X501969D03*
X498032D03*
X494095D03*
X490158D03*
X486221D03*
X482284D03*
X478347D03*
X474410D03*
X470473D03*
X466536D03*
X462599D03*
X458662D03*
X454725D03*
X450787D03*
X509843Y301182D03*
X505906D03*
X501969D03*
X498032D03*
X494095D03*
X490158D03*
X486221D03*
X482284D03*
X478347D03*
X474410D03*
X470473D03*
X466536D03*
X462599D03*
X458662D03*
X454725D03*
X450787D03*
X509843Y305119D03*
X505906D03*
X501969D03*
X498032D03*
X494095D03*
X490158D03*
X486221D03*
X482284D03*
X478347D03*
X474410D03*
X470473D03*
X466536D03*
X462599D03*
X458662D03*
X454725D03*
X450787D03*
X509843Y309056D03*
X505906D03*
X501969D03*
X498032D03*
X494095D03*
X490158D03*
X486221D03*
X482284D03*
X478347D03*
X474410D03*
X470473D03*
X466536D03*
X462599D03*
X458662D03*
X454725D03*
X450787D03*
X509843Y312993D03*
X505906D03*
X501969D03*
X498032D03*
X494095D03*
X490158D03*
X486221D03*
X482284D03*
X478347D03*
X474410D03*
X470473D03*
X466536D03*
X462599D03*
X458662D03*
X454725D03*
X450787D03*
X501969Y316930D03*
X498032D03*
X494095D03*
X490158D03*
X486221D03*
X482284D03*
X478347D03*
X474410D03*
X470473D03*
X466536D03*
X462599D03*
X458662D03*
X454725D03*
X450787D03*
X501969Y320867D03*
X498032D03*
X494095D03*
X490158D03*
X486221D03*
X482284D03*
X478347D03*
X474410D03*
X470473D03*
X466536D03*
X462599D03*
X458662D03*
X454725D03*
X450787D03*
X501969Y324804D03*
X498032D03*
X494095D03*
X490158D03*
X486221D03*
X482284D03*
X478347D03*
X474410D03*
X470473D03*
X466536D03*
X462599D03*
X458662D03*
X454725D03*
X450787D03*
X513780Y214567D03*
Y218504D03*
Y222441D03*
Y226378D03*
Y230315D03*
Y234252D03*
Y238189D03*
Y242126D03*
Y246063D03*
Y250000D03*
Y253937D03*
Y257874D03*
Y261811D03*
Y265749D03*
Y269686D03*
Y273623D03*
Y277560D03*
Y281497D03*
Y285434D03*
Y289371D03*
Y293308D03*
Y297245D03*
Y301182D03*
Y305119D03*
Y309056D03*
Y312993D03*
G54D68*
X261713Y386027D03*
X259744D03*
X257776D03*
X255807D03*
X253839D03*
X251870D03*
X249901D03*
X247933D03*
X245964D03*
X243996D03*
X242027D03*
Y405313D03*
X243996D03*
X245964D03*
X247933D03*
X249901D03*
X251870D03*
X253839D03*
X255807D03*
X257776D03*
X259744D03*
X261713D03*
G54D86*
X621320Y299289D03*
Y297319D03*
Y295354D03*
X605020D03*
Y297319D03*
Y299289D03*
X614220Y361815D03*
X605020D03*
X621320Y341633D03*
Y339668D03*
Y337698D03*
Y335728D03*
Y333763D03*
X605020D03*
Y335728D03*
Y337698D03*
Y339668D03*
Y341633D03*
X621320Y303224D03*
Y301259D03*
X605020D03*
Y303224D03*
X614220Y367725D03*
Y365755D03*
Y363785D03*
X605020D03*
Y365755D03*
Y367725D03*
X614220Y390105D03*
Y388135D03*
Y386165D03*
Y384195D03*
X605020D03*
Y386165D03*
Y388135D03*
Y390105D03*
X762337Y278194D03*
Y280164D03*
Y282134D03*
Y284104D03*
X771537D03*
Y282134D03*
Y280164D03*
Y278194D03*
G54D59*
X177800Y131500D03*
G54D95*
X690890Y419020D03*
X687015Y411520D03*
X694765D03*
X701325Y420610D03*
X709075D03*
X734040Y441340D03*
X730165Y433840D03*
X737915D03*
X719850Y437470D03*
X715975Y429970D03*
X723725D03*
X705200Y428110D03*
G54D77*
G01X-34018Y-300855D02*
G02I-12000J0D01*
G01X-39168D02*
G02I-6850J0D01*
G01X-30018D02*
X-62018D01*
G01X-30018Y-316855D02*
Y-396855D01*
G01D02*
X1320682D01*
G01X-30018Y-352355D02*
X1320682D01*
G01X-46018Y-316855D02*
Y-284855D01*
G01X-30018Y-316855D02*
X1320682D01*
G01X533182D02*
Y-396855D01*
G01X670682Y-316855D02*
Y-396855D01*
G01X785682Y-316855D02*
Y-396855D01*
G01X953182Y-316855D02*
Y-396855D01*
G01X1123182Y-316855D02*
Y-396855D01*
G01X1320682Y-316855D02*
Y-396855D01*
G01X1348682Y-300855D02*
G02I-12000J0D01*
G01X1343532D02*
G02I-6850J0D01*
G01X1336682Y-316855D02*
Y-284855D01*
G01X1352682Y-300855D02*
X1320682D01*
X399606Y202756D03*
X395669D03*
X399606Y206693D03*
X395669D03*
X391732D03*
X399606Y210630D03*
X395669D03*
X391732D03*
X399606Y316930D03*
X395669D03*
X391732D03*
X399606Y320867D03*
X395669D03*
X391732D03*
X399606Y324804D03*
X395669D03*
X509843Y202756D03*
X505906D03*
X509843Y206693D03*
X505906D03*
X509843Y210630D03*
X505906D03*
X509843Y316930D03*
X505906D03*
X509843Y320867D03*
X505906D03*
X509843Y324804D03*
X505906D03*
X513780Y206693D03*
Y210630D03*
Y316930D03*
Y320867D03*
G54D78*
X496499Y175070D03*
X494199D03*
X506245Y175012D03*
X503945D03*
X496499Y177270D03*
X494199D03*
X506245Y177212D03*
X503945D03*
X516370Y174954D03*
X514070D03*
X526495Y174896D03*
X524195D03*
X516370Y177154D03*
X514070D03*
X526495Y177096D03*
X524195D03*
G54D96*
X673161Y371204D03*
Y367267D03*
X662745Y369236D03*
G54D69*
X236820Y417395D03*
Y439281D03*
G54D87*
X632800Y341500D03*
X629200D03*
X632800Y302891D03*
X629200D03*
X693900Y302100D03*
X690300D03*
G54D79*
X571249Y127362D03*
X573401Y127820D03*
X570771Y129612D03*
X572923Y130070D03*
X584086Y174012D03*
X586238Y174470D03*
X579993Y158187D03*
X582145Y158645D03*
X579515Y160436D03*
X581667Y160894D03*
X589314Y149359D03*
X591466Y149817D03*
X588836Y151608D03*
X590988Y152066D03*
X582353Y138181D03*
X584505Y138639D03*
X581875Y140430D03*
X584027Y140888D03*
X583321Y214047D03*
X585473Y214505D03*
X582842Y216296D03*
X584994Y216754D03*
X579391Y198464D03*
X581543Y198922D03*
X578913Y200713D03*
X581065Y201171D03*
X575189Y182722D03*
X577341Y183180D03*
X574711Y184971D03*
X576863Y185429D03*
X583608Y176262D03*
X585760Y176720D03*
G54D88*
X629400Y405234D03*
X609400D03*
X619400Y417046D03*
X599400D03*
X761520Y350206D03*
X781520D03*
X771520Y338394D03*
X791520D03*
G54D97*
X665245Y373173D03*
G54D98*
X676311Y379078D03*
Y377110D03*
Y375141D03*
Y373173D03*
X659595Y379078D03*
Y375141D03*
Y377110D03*
G54D89*
X604400Y456100D03*
G54D99*
X674843Y382515D03*
X672874D03*
X663032D03*
X661063D03*
X665000D03*
X666969D03*
X668937D03*
X670906D03*
M02*
